FILE_TYPE = MACRO_DRAWING;
SET COLOR_WIRE YELLOW;
SET COLOR_PROP ORANGE;
SET COLOR_DOT WHITE;
SET COLOR_ARC YELLOW;
SET COLOR_BODY GREEN;
SET COLOR_NOTE PURPLE;
SET PROP_DISPLAY VALUE;
SET PAGE_NUMBER P74;
FORCEADD Q_CAP..1
(-4250 -1650);
FORCEPROP 1 LAST PART_NUMBER CH622KMEB01
J 0
(-4200 -1800);
DISPLAY 0.638298 (-4200 -1800);
DISPLAY INVISIBLE (-4200 -1800);
FORCEPROP 1 LAST MATERIAL X6S
J 0
(-4200 -1750);
DISPLAY 0.638298 (-4200 -1750);
FORCEPROP 1 LAST PACK_TYPE C0402
J 0
(-4200 -1850);
DISPLAY 0.638298 (-4200 -1850);
FORCEPROP 1 LAST VALUE 22UF
J 0
(-4200 -1600);
DISPLAY 0.638298 (-4200 -1600);
FORCEPROP 1 LAST TOLERANCE 20%
J 0
(-4200 -1700);
DISPLAY 0.638298 (-4200 -1700);
FORCEPROP 1 LAST VOLTAGE 4V
J 0
(-4200 -1650);
DISPLAY 0.638298 (-4200 -1650);
FORCEPROP 1 LAST $LOCATION C400
J 0
(-4200 -1550);
DISPLAY 0.978723 (-4200 -1550);
FORCEPROP 1 LASTPIN (-4250 -1550) $PN 1
J 0
(-4240 -1570);
DISPLAY 0.787234 (-4240 -1570);
FORCEPROP 1 LASTPIN (-4250 -1750) $PN 2
J 0
(-4240 -1770);
DISPLAY 0.787234 (-4240 -1770);
FORCEPROP 2 LAST CDS_LIB pure_quanta
J 0
(-4250 -1650);
PAINT MONO (-4250 -1650);
DISPLAY INVISIBLE (-4250 -1650);
FORCEPROP 2 LAST CDS_LOCATION C400
J 0
(-4200 -1450);
DISPLAY 1.021277 (-4200 -1450);
DISPLAY INVISIBLE (-4200 -1450);
FORCEPROP 2 LAST $SEC 1
J 0
(-4200 -1450);
DISPLAY 0.680851 (-4200 -1450);
PAINT MONO (-4200 -1450);
DISPLAY INVISIBLE (-4200 -1450);
FORCEPROP 2 LAST CDS_SEC 1
J 0
(-4200 -1450);
DISPLAY 1.021277 (-4200 -1450);
DISPLAY INVISIBLE (-4200 -1450);
FORCEPROP 1 LAST PATH I1
J 0
(-4200 -1500);
DISPLAY 0.978723 (-4200 -1500);
PAINT WHITE (-4200 -1500);
DISPLAY INVISIBLE (-4200 -1500);
FORCEADD Q_CAP..1
(-1100 -1650);
FORCEPROP 1 LAST PART_NUMBER CH622KMEB01
J 0
(-1050 -1800);
DISPLAY 0.638298 (-1050 -1800);
DISPLAY INVISIBLE (-1050 -1800);
FORCEPROP 1 LAST MATERIAL X6S
J 0
(-1050 -1750);
DISPLAY 0.638298 (-1050 -1750);
FORCEPROP 1 LAST PACK_TYPE C0402
J 0
(-1050 -1850);
DISPLAY 0.638298 (-1050 -1850);
FORCEPROP 1 LAST VALUE 22UF
J 0
(-1050 -1600);
DISPLAY 0.638298 (-1050 -1600);
FORCEPROP 1 LAST TOLERANCE 20%
J 0
(-1050 -1700);
DISPLAY 0.638298 (-1050 -1700);
FORCEPROP 1 LAST VOLTAGE 4V
J 0
(-1050 -1650);
DISPLAY 0.638298 (-1050 -1650);
FORCEPROP 1 LAST $LOCATION C413
J 0
(-1050 -1550);
DISPLAY 0.978723 (-1050 -1550);
FORCEPROP 1 LASTPIN (-1100 -1550) $PN 1
J 0
(-1090 -1570);
DISPLAY 0.787234 (-1090 -1570);
FORCEPROP 1 LASTPIN (-1100 -1750) $PN 2
J 0
(-1090 -1770);
DISPLAY 0.787234 (-1090 -1770);
FORCEPROP 2 LAST CDS_LIB pure_quanta
J 0
(-1100 -1650);
PAINT MONO (-1100 -1650);
DISPLAY INVISIBLE (-1100 -1650);
FORCEPROP 2 LAST CDS_LOCATION C413
J 0
(-1050 -1450);
DISPLAY 1.021277 (-1050 -1450);
DISPLAY INVISIBLE (-1050 -1450);
FORCEPROP 2 LAST $SEC 1
J 0
(-1050 -1450);
DISPLAY 0.680851 (-1050 -1450);
PAINT MONO (-1050 -1450);
DISPLAY INVISIBLE (-1050 -1450);
FORCEPROP 2 LAST CDS_SEC 1
J 0
(-1050 -1450);
DISPLAY 1.021277 (-1050 -1450);
DISPLAY INVISIBLE (-1050 -1450);
FORCEPROP 1 LAST PATH I10
J 0
(-1050 -1500);
DISPLAY 0.978723 (-1050 -1500);
PAINT WHITE (-1050 -1500);
DISPLAY INVISIBLE (-1050 -1500);
FORCEADD Q_CAP..1
(1475 -850);
FORCEPROP 1 LAST PART_NUMBER CH622KMEB01
J 0
(1525 -1000);
DISPLAY 0.638298 (1525 -1000);
DISPLAY INVISIBLE (1525 -1000);
FORCEPROP 1 LAST MATERIAL X6S
J 0
(1525 -950);
DISPLAY 0.638298 (1525 -950);
FORCEPROP 1 LAST PACK_TYPE C0402
J 0
(1525 -1050);
DISPLAY 0.638298 (1525 -1050);
FORCEPROP 1 LAST TOLERANCE 20%
J 0
(1525 -900);
DISPLAY 0.638298 (1525 -900);
FORCEPROP 1 LAST VOLTAGE 4V
J 0
(1525 -850);
DISPLAY 0.638298 (1525 -850);
FORCEPROP 1 LAST VALUE 22UF
J 0
(1525 -800);
DISPLAY 0.638298 (1525 -800);
FORCEPROP 1 LAST $LOCATION C420
J 0
(1525 -750);
DISPLAY 0.978723 (1525 -750);
FORCEPROP 1 LASTPIN (1475 -750) $PN 1
J 0
(1485 -770);
DISPLAY 0.787234 (1485 -770);
FORCEPROP 1 LASTPIN (1475 -950) $PN 2
J 0
(1485 -970);
DISPLAY 0.787234 (1485 -970);
FORCEPROP 2 LAST CDS_LIB pure_quanta
J 0
(1475 -850);
PAINT MONO (1475 -850);
DISPLAY INVISIBLE (1475 -850);
FORCEPROP 2 LAST CDS_LOCATION C420
J 0
(1525 -650);
DISPLAY 1.021277 (1525 -650);
DISPLAY INVISIBLE (1525 -650);
FORCEPROP 2 LAST $SEC 1
J 0
(1525 -650);
DISPLAY 0.680851 (1525 -650);
PAINT MONO (1525 -650);
DISPLAY INVISIBLE (1525 -650);
FORCEPROP 2 LAST CDS_SEC 1
J 0
(1525 -650);
DISPLAY 1.021277 (1525 -650);
DISPLAY INVISIBLE (1525 -650);
FORCEPROP 1 LAST PATH I100
J 0
(1525 -700);
DISPLAY 0.978723 (1525 -700);
PAINT WHITE (1525 -700);
DISPLAY INVISIBLE (1525 -700);
FORCEADD UNIVERSAL_GND..1
(1025 -425);
FORCEPROP 3 LASTPIN (1025 -375) SIG_NAME GND\g
J 0
(1035 -365);
DISPLAY 0.659574 (1035 -365);
PAINT MONO (1035 -365);
DISPLAY INVISIBLE (1035 -365);
FORCEPROP 2 LAST CDS_LIB logical_power
J 0
(1025 -425);
DISPLAY INVISIBLE (1025 -425);
FORCEPROP 1 LAST HDL_POWER GND
J 1
(1050 -500);
DISPLAY 0.872340 (1050 -500);
PAINT GREEN (1050 -500);
DISPLAY INVISIBLE (1050 -500);
FORCEPROP 1 LAST PATH I101
J 0
(1100 -425);
DISPLAY 0.872340 (1100 -425);
PAINT AQUA (1100 -425);
DISPLAY INVISIBLE (1100 -425);
FORCEADD Q_CAP..1
(1025 -150);
FORCEPROP 1 LAST PART_NUMBER CH622KMEB01
J 0
(1075 -300);
DISPLAY 0.638298 (1075 -300);
DISPLAY INVISIBLE (1075 -300);
FORCEPROP 1 LAST PACK_TYPE C0402
J 0
(1075 -350);
DISPLAY 0.638298 (1075 -350);
FORCEPROP 1 LAST VOLTAGE 4V
J 0
(1075 -150);
DISPLAY 0.638298 (1075 -150);
FORCEPROP 1 LAST MATERIAL X6S
J 0
(1075 -250);
DISPLAY 0.638298 (1075 -250);
FORCEPROP 1 LAST TOLERANCE 20%
J 0
(1075 -200);
DISPLAY 0.638298 (1075 -200);
FORCEPROP 1 LAST VALUE 22UF
J 0
(1075 -100);
DISPLAY 0.638298 (1075 -100);
FORCEPROP 1 LAST $LOCATION C590
J 0
(1075 -50);
DISPLAY 0.978723 (1075 -50);
FORCEPROP 1 LASTPIN (1025 -50) $PN 1
J 0
(1035 -70);
DISPLAY 0.787234 (1035 -70);
PAINT MONO (1035 -70);
FORCEPROP 1 LASTPIN (1025 -250) $PN 2
J 0
(1035 -270);
DISPLAY 0.787234 (1035 -270);
PAINT MONO (1035 -270);
FORCEPROP 2 LAST CDS_LIB pure_quanta
J 0
(1025 -150);
DISPLAY INVISIBLE (1025 -150);
FORCEPROP 0 LAST CDS_LOCATION C590
J 0
(1075 0);
DISPLAY 1.021277 (1075 0);
DISPLAY INVISIBLE (1075 0);
FORCEPROP 0 LAST $SEC 1
J 0
(1075 0);
DISPLAY 0.680851 (1075 0);
PAINT MONO (1075 0);
DISPLAY INVISIBLE (1075 0);
FORCEPROP 0 LAST CDS_SEC 1
J 0
(1075 0);
DISPLAY 1.021277 (1075 0);
DISPLAY INVISIBLE (1075 0);
FORCEPROP 1 LAST PATH I102
J 0
(1075 0);
DISPLAY 0.978723 (1075 0);
PAINT WHITE (1075 0);
DISPLAY INVISIBLE (1075 0);
FORCEADD Q_CAP..1
(1925 -850);
FORCEPROP 1 LAST PART_NUMBER CH622KMEB01
J 0
(1975 -1000);
DISPLAY 0.638298 (1975 -1000);
DISPLAY INVISIBLE (1975 -1000);
FORCEPROP 1 LAST PACK_TYPE C0402
J 0
(1975 -1050);
DISPLAY 0.638298 (1975 -1050);
FORCEPROP 1 LAST MATERIAL X6S
J 0
(1975 -950);
DISPLAY 0.638298 (1975 -950);
FORCEPROP 1 LAST TOLERANCE 20%
J 0
(1975 -900);
DISPLAY 0.638298 (1975 -900);
FORCEPROP 1 LAST VOLTAGE 4V
J 0
(1975 -850);
DISPLAY 0.638298 (1975 -850);
FORCEPROP 1 LAST VALUE 22UF
J 0
(1975 -800);
DISPLAY 0.638298 (1975 -800);
FORCEPROP 1 LAST $LOCATION C421
J 0
(1975 -750);
DISPLAY 0.978723 (1975 -750);
FORCEPROP 1 LASTPIN (1925 -750) $PN 1
J 0
(1935 -770);
DISPLAY 0.787234 (1935 -770);
FORCEPROP 1 LASTPIN (1925 -950) $PN 2
J 0
(1935 -970);
DISPLAY 0.787234 (1935 -970);
FORCEPROP 2 LAST CDS_LIB pure_quanta
J 0
(1925 -850);
PAINT MONO (1925 -850);
DISPLAY INVISIBLE (1925 -850);
FORCEPROP 2 LAST CDS_LOCATION C421
J 0
(1975 -650);
DISPLAY 1.021277 (1975 -650);
DISPLAY INVISIBLE (1975 -650);
FORCEPROP 2 LAST $SEC 1
J 0
(1975 -650);
DISPLAY 0.680851 (1975 -650);
PAINT MONO (1975 -650);
DISPLAY INVISIBLE (1975 -650);
FORCEPROP 2 LAST CDS_SEC 1
J 0
(1975 -650);
DISPLAY 1.021277 (1975 -650);
DISPLAY INVISIBLE (1975 -650);
FORCEPROP 1 LAST PATH I103
J 0
(1975 -700);
DISPLAY 0.978723 (1975 -700);
PAINT WHITE (1975 -700);
DISPLAY INVISIBLE (1975 -700);
FORCEADD UNIVERSAL_POWER..1
(1025 125);
FORCEPROP 3 LASTPIN (1025 75) SIG_NAME PVNN_MAIN_CPU0\g
J 0
(1035 85);
DISPLAY 0.659574 (1035 85);
PAINT MONO (1035 85);
DISPLAY INVISIBLE (1035 85);
FORCEPROP 1 LAST HDL_POWER PVNN_MAIN_CPU0
J 1
(1075 175);
DISPLAY 1.085106 (1075 175);
PAINT GREEN (1075 175);
FORCEPROP 2 LAST CDS_LIB logical_power
J 0
(1025 125);
DISPLAY INVISIBLE (1025 125);
FORCEPROP 1 LAST PATH I104
J 0
(1075 150);
DISPLAY 0.872340 (1075 150);
PAINT AQUA (1075 150);
DISPLAY INVISIBLE (1075 150);
FORCEADD Q_CAP..1
(1175 725);
FORCEPROP 1 LAST PART_NUMBER CH622KMEB01
J 0
(1225 575);
DISPLAY 0.638298 (1225 575);
DISPLAY INVISIBLE (1225 575);
FORCEPROP 1 LAST PACK_TYPE C0402
J 0
(1225 525);
DISPLAY 0.638298 (1225 525);
FORCEPROP 1 LAST VOLTAGE 4V
J 0
(1225 725);
DISPLAY 0.638298 (1225 725);
FORCEPROP 1 LAST MATERIAL X6S
J 0
(1225 625);
DISPLAY 0.638298 (1225 625);
FORCEPROP 1 LAST VALUE 22UF
J 0
(1225 775);
DISPLAY 0.638298 (1225 775);
FORCEPROP 1 LAST TOLERANCE 20%
J 0
(1225 675);
DISPLAY 0.638298 (1225 675);
FORCEPROP 1 LAST $LOCATION C1017
J 0
(1225 825);
DISPLAY 0.638298 (1225 825);
FORCEPROP 1 LASTPIN (1175 825) $PN 1
J 0
(1185 805);
DISPLAY 0.787234 (1185 805);
FORCEPROP 1 LASTPIN (1175 625) $PN 2
J 0
(1185 605);
DISPLAY 0.787234 (1185 605);
FORCEPROP 2 LAST CDS_LIB pure_quanta
J 0
(1175 725);
PAINT MONO (1175 725);
DISPLAY INVISIBLE (1175 725);
FORCEPROP 2 LAST CDS_LOCATION C1017
J 0
(1225 925);
DISPLAY 1.021277 (1225 925);
DISPLAY INVISIBLE (1225 925);
FORCEPROP 2 LAST $SEC 1
J 0
(1225 925);
DISPLAY 0.680851 (1225 925);
PAINT MONO (1225 925);
DISPLAY INVISIBLE (1225 925);
FORCEPROP 2 LAST CDS_SEC 1
J 0
(1225 925);
DISPLAY 1.021277 (1225 925);
DISPLAY INVISIBLE (1225 925);
FORCEPROP 1 LAST PATH I105
J 0
(1225 875);
DISPLAY 0.978723 (1225 875);
PAINT WHITE (1225 875);
DISPLAY INVISIBLE (1225 875);
FORCEADD Q_CAP..1
(1625 725);
FORCEPROP 1 LAST PART_NUMBER CH622KMEB01
J 0
(1675 575);
DISPLAY 0.638298 (1675 575);
DISPLAY INVISIBLE (1675 575);
FORCEPROP 1 LAST PACK_TYPE C0402
J 0
(1675 525);
DISPLAY 0.638298 (1675 525);
FORCEPROP 1 LAST MATERIAL X6S
J 0
(1675 625);
DISPLAY 0.638298 (1675 625);
FORCEPROP 1 LAST TOLERANCE 20%
J 0
(1675 675);
DISPLAY 0.638298 (1675 675);
FORCEPROP 1 LAST VALUE 22UF
J 0
(1675 775);
DISPLAY 0.638298 (1675 775);
FORCEPROP 1 LAST VOLTAGE 4V
J 0
(1675 725);
DISPLAY 0.638298 (1675 725);
FORCEPROP 1 LAST $LOCATION C1021
J 0
(1675 825);
DISPLAY 0.638298 (1675 825);
FORCEPROP 1 LASTPIN (1625 825) $PN 1
J 0
(1635 805);
DISPLAY 0.787234 (1635 805);
FORCEPROP 1 LASTPIN (1625 625) $PN 2
J 0
(1635 605);
DISPLAY 0.787234 (1635 605);
FORCEPROP 2 LAST CDS_LIB pure_quanta
J 0
(1625 725);
PAINT MONO (1625 725);
DISPLAY INVISIBLE (1625 725);
FORCEPROP 2 LAST CDS_LOCATION C1021
J 0
(1675 925);
DISPLAY 1.021277 (1675 925);
DISPLAY INVISIBLE (1675 925);
FORCEPROP 2 LAST $SEC 1
J 0
(1675 925);
DISPLAY 0.680851 (1675 925);
PAINT MONO (1675 925);
DISPLAY INVISIBLE (1675 925);
FORCEPROP 2 LAST CDS_SEC 1
J 0
(1675 925);
DISPLAY 1.021277 (1675 925);
DISPLAY INVISIBLE (1675 925);
FORCEPROP 1 LAST PATH I106
J 0
(1675 875);
DISPLAY 0.978723 (1675 875);
PAINT WHITE (1675 875);
DISPLAY INVISIBLE (1675 875);
FORCEADD Q_CAP..1
(2375 -850);
FORCEPROP 1 LAST PART_NUMBER CH622KMEB01
J 0
(2425 -1000);
DISPLAY 0.638298 (2425 -1000);
DISPLAY INVISIBLE (2425 -1000);
FORCEPROP 1 LAST PACK_TYPE C0402
J 0
(2425 -1050);
DISPLAY 0.638298 (2425 -1050);
FORCEPROP 1 LAST MATERIAL X6S
J 0
(2425 -950);
DISPLAY 0.638298 (2425 -950);
FORCEPROP 1 LAST TOLERANCE 20%
J 0
(2425 -900);
DISPLAY 0.638298 (2425 -900);
FORCEPROP 1 LAST VOLTAGE 4V
J 0
(2425 -850);
DISPLAY 0.638298 (2425 -850);
FORCEPROP 1 LAST VALUE 22UF
J 0
(2425 -800);
DISPLAY 0.638298 (2425 -800);
FORCEPROP 1 LAST $LOCATION C422
J 0
(2425 -750);
DISPLAY 0.978723 (2425 -750);
FORCEPROP 1 LASTPIN (2375 -750) $PN 1
J 0
(2385 -770);
DISPLAY 0.787234 (2385 -770);
FORCEPROP 1 LASTPIN (2375 -950) $PN 2
J 0
(2385 -970);
DISPLAY 0.787234 (2385 -970);
FORCEPROP 2 LAST CDS_LIB pure_quanta
J 0
(2375 -850);
PAINT MONO (2375 -850);
DISPLAY INVISIBLE (2375 -850);
FORCEPROP 2 LAST CDS_LOCATION C422
J 0
(2425 -650);
DISPLAY 1.021277 (2425 -650);
DISPLAY INVISIBLE (2425 -650);
FORCEPROP 2 LAST $SEC 1
J 0
(2425 -650);
DISPLAY 0.680851 (2425 -650);
PAINT MONO (2425 -650);
DISPLAY INVISIBLE (2425 -650);
FORCEPROP 2 LAST CDS_SEC 1
J 0
(2425 -650);
DISPLAY 1.021277 (2425 -650);
DISPLAY INVISIBLE (2425 -650);
FORCEPROP 1 LAST PATH I107
J 0
(2425 -700);
DISPLAY 0.978723 (2425 -700);
PAINT WHITE (2425 -700);
DISPLAY INVISIBLE (2425 -700);
FORCEADD Q_CAP..1
(2075 725);
FORCEPROP 1 LAST PART_NUMBER CH622KMEB01
J 0
(2125 575);
DISPLAY 0.638298 (2125 575);
DISPLAY INVISIBLE (2125 575);
FORCEPROP 1 LAST PACK_TYPE C0402
J 0
(2125 525);
DISPLAY 0.638298 (2125 525);
FORCEPROP 1 LAST VOLTAGE 4V
J 0
(2125 725);
DISPLAY 0.638298 (2125 725);
FORCEPROP 1 LAST VALUE 22UF
J 0
(2125 775);
DISPLAY 0.638298 (2125 775);
FORCEPROP 1 LAST TOLERANCE 20%
J 0
(2125 675);
DISPLAY 0.638298 (2125 675);
FORCEPROP 1 LAST MATERIAL X6S
J 0
(2125 625);
DISPLAY 0.638298 (2125 625);
FORCEPROP 1 LAST $LOCATION C1025
J 0
(2125 825);
DISPLAY 0.638298 (2125 825);
FORCEPROP 1 LASTPIN (2075 825) $PN 1
J 0
(2085 805);
DISPLAY 0.787234 (2085 805);
FORCEPROP 1 LASTPIN (2075 625) $PN 2
J 0
(2085 605);
DISPLAY 0.787234 (2085 605);
FORCEPROP 2 LAST CDS_LIB pure_quanta
J 0
(2075 725);
PAINT MONO (2075 725);
DISPLAY INVISIBLE (2075 725);
FORCEPROP 2 LAST CDS_LOCATION C1025
J 0
(2125 925);
DISPLAY 1.021277 (2125 925);
DISPLAY INVISIBLE (2125 925);
FORCEPROP 2 LAST $SEC 1
J 0
(2125 925);
DISPLAY 0.680851 (2125 925);
PAINT MONO (2125 925);
DISPLAY INVISIBLE (2125 925);
FORCEPROP 2 LAST CDS_SEC 1
J 0
(2125 925);
DISPLAY 1.021277 (2125 925);
DISPLAY INVISIBLE (2125 925);
FORCEPROP 1 LAST PATH I108
J 0
(2125 875);
DISPLAY 0.978723 (2125 875);
PAINT WHITE (2125 875);
DISPLAY INVISIBLE (2125 875);
FORCEADD Q_CAP..1
(2525 725);
FORCEPROP 1 LAST PART_NUMBER CH622KMEB01
J 0
(2575 575);
DISPLAY 0.638298 (2575 575);
DISPLAY INVISIBLE (2575 575);
FORCEPROP 1 LAST PACK_TYPE C0402
J 0
(2575 525);
DISPLAY 0.638298 (2575 525);
FORCEPROP 1 LAST TOLERANCE 20%
J 0
(2575 675);
DISPLAY 0.638298 (2575 675);
FORCEPROP 1 LAST MATERIAL X6S
J 0
(2575 625);
DISPLAY 0.638298 (2575 625);
FORCEPROP 1 LAST VOLTAGE 4V
J 0
(2575 725);
DISPLAY 0.638298 (2575 725);
FORCEPROP 1 LAST VALUE 22UF
J 0
(2575 775);
DISPLAY 0.638298 (2575 775);
FORCEPROP 1 LAST $LOCATION C1029
J 0
(2575 825);
DISPLAY 0.638298 (2575 825);
FORCEPROP 1 LASTPIN (2525 825) $PN 1
J 0
(2535 805);
DISPLAY 0.787234 (2535 805);
FORCEPROP 1 LASTPIN (2525 625) $PN 2
J 0
(2535 605);
DISPLAY 0.787234 (2535 605);
FORCEPROP 2 LAST CDS_LIB pure_quanta
J 0
(2525 725);
PAINT MONO (2525 725);
DISPLAY INVISIBLE (2525 725);
FORCEPROP 2 LAST CDS_LOCATION C1029
J 0
(2575 925);
DISPLAY 1.021277 (2575 925);
DISPLAY INVISIBLE (2575 925);
FORCEPROP 2 LAST $SEC 1
J 0
(2575 925);
DISPLAY 0.680851 (2575 925);
PAINT MONO (2575 925);
DISPLAY INVISIBLE (2575 925);
FORCEPROP 2 LAST CDS_SEC 1
J 0
(2575 925);
DISPLAY 1.021277 (2575 925);
DISPLAY INVISIBLE (2575 925);
FORCEPROP 1 LAST PATH I109
J 0
(2575 875);
DISPLAY 0.978723 (2575 875);
PAINT WHITE (2575 875);
DISPLAY INVISIBLE (2575 875);
FORCEADD Q_CAP..1
(-4250 -850);
FORCEPROP 1 LAST PART_NUMBER CH622KMEB01
J 0
(-4200 -1000);
DISPLAY 0.638298 (-4200 -1000);
DISPLAY INVISIBLE (-4200 -1000);
FORCEPROP 1 LAST TOLERANCE 20%
J 0
(-4200 -900);
DISPLAY 0.638298 (-4200 -900);
FORCEPROP 1 LAST PACK_TYPE C0402
J 0
(-4200 -1050);
DISPLAY 0.638298 (-4200 -1050);
FORCEPROP 1 LAST VOLTAGE 4V
J 0
(-4200 -850);
DISPLAY 0.638298 (-4200 -850);
FORCEPROP 1 LAST MATERIAL X6S
J 0
(-4200 -950);
DISPLAY 0.638298 (-4200 -950);
FORCEPROP 1 LAST VALUE 22UF
J 0
(-4200 -800);
DISPLAY 0.638298 (-4200 -800);
FORCEPROP 1 LAST $LOCATION C399
J 0
(-4200 -750);
DISPLAY 0.978723 (-4200 -750);
FORCEPROP 1 LASTPIN (-4250 -750) $PN 1
J 0
(-4240 -770);
DISPLAY 0.787234 (-4240 -770);
FORCEPROP 1 LASTPIN (-4250 -950) $PN 2
J 0
(-4240 -970);
DISPLAY 0.787234 (-4240 -970);
FORCEPROP 2 LAST CDS_LIB pure_quanta
J 0
(-4250 -850);
PAINT MONO (-4250 -850);
DISPLAY INVISIBLE (-4250 -850);
FORCEPROP 2 LAST CDS_LOCATION C399
J 0
(-4200 -650);
DISPLAY 1.021277 (-4200 -650);
DISPLAY INVISIBLE (-4200 -650);
FORCEPROP 2 LAST $SEC 1
J 0
(-4200 -650);
DISPLAY 0.680851 (-4200 -650);
PAINT MONO (-4200 -650);
DISPLAY INVISIBLE (-4200 -650);
FORCEPROP 2 LAST CDS_SEC 1
J 0
(-4200 -650);
DISPLAY 1.021277 (-4200 -650);
DISPLAY INVISIBLE (-4200 -650);
FORCEPROP 1 LAST PATH I11
J 0
(-4200 -700);
DISPLAY 0.978723 (-4200 -700);
PAINT WHITE (-4200 -700);
DISPLAY INVISIBLE (-4200 -700);
FORCEADD Q_CAP..1
(2975 725);
FORCEPROP 1 LAST PART_NUMBER CH622KMEB01
J 0
(3025 575);
DISPLAY 0.638298 (3025 575);
DISPLAY INVISIBLE (3025 575);
FORCEPROP 1 LAST PACK_TYPE C0402
J 0
(3025 525);
DISPLAY 0.638298 (3025 525);
FORCEPROP 1 LAST TOLERANCE 20%
J 0
(3025 675);
DISPLAY 0.638298 (3025 675);
FORCEPROP 1 LAST VALUE 22UF
J 0
(3025 775);
DISPLAY 0.638298 (3025 775);
FORCEPROP 1 LAST VOLTAGE 4V
J 0
(3025 725);
DISPLAY 0.638298 (3025 725);
FORCEPROP 1 LAST MATERIAL X6S
J 0
(3025 625);
DISPLAY 0.638298 (3025 625);
FORCEPROP 1 LAST $LOCATION C1033
J 0
(3025 825);
DISPLAY 0.638298 (3025 825);
FORCEPROP 1 LASTPIN (2975 825) $PN 1
J 0
(2985 805);
DISPLAY 0.787234 (2985 805);
FORCEPROP 1 LASTPIN (2975 625) $PN 2
J 0
(2985 605);
DISPLAY 0.787234 (2985 605);
FORCEPROP 2 LAST CDS_LIB pure_quanta
J 0
(2975 725);
PAINT MONO (2975 725);
DISPLAY INVISIBLE (2975 725);
FORCEPROP 2 LAST CDS_LOCATION C1033
J 0
(3025 925);
DISPLAY 1.021277 (3025 925);
DISPLAY INVISIBLE (3025 925);
FORCEPROP 2 LAST $SEC 1
J 0
(3025 925);
DISPLAY 0.680851 (3025 925);
PAINT MONO (3025 925);
DISPLAY INVISIBLE (3025 925);
FORCEPROP 2 LAST CDS_SEC 1
J 0
(3025 925);
DISPLAY 1.021277 (3025 925);
DISPLAY INVISIBLE (3025 925);
FORCEPROP 1 LAST PATH I110
J 0
(3025 875);
DISPLAY 0.978723 (3025 875);
PAINT WHITE (3025 875);
DISPLAY INVISIBLE (3025 875);
FORCEADD Q_CAP..1
(1175 1500);
FORCEPROP 1 LAST PART_NUMBER CH622KMEB01
J 0
(1225 1350);
DISPLAY 0.638298 (1225 1350);
DISPLAY INVISIBLE (1225 1350);
FORCEPROP 1 LAST MATERIAL X6S
J 0
(1225 1400);
DISPLAY 0.638298 (1225 1400);
FORCEPROP 1 LAST PACK_TYPE C0402
J 0
(1225 1300);
DISPLAY 0.638298 (1225 1300);
FORCEPROP 1 LAST VOLTAGE 4V
J 0
(1225 1500);
DISPLAY 0.638298 (1225 1500);
FORCEPROP 1 LAST VALUE 22UF
J 0
(1225 1550);
DISPLAY 0.638298 (1225 1550);
FORCEPROP 1 LAST TOLERANCE 20%
J 0
(1225 1450);
DISPLAY 0.638298 (1225 1450);
FORCEPROP 1 LAST $LOCATION C1016
J 0
(1225 1600);
DISPLAY 0.638298 (1225 1600);
FORCEPROP 1 LASTPIN (1175 1600) $PN 1
J 0
(1185 1580);
DISPLAY 0.787234 (1185 1580);
FORCEPROP 1 LASTPIN (1175 1400) $PN 2
J 0
(1185 1380);
DISPLAY 0.787234 (1185 1380);
FORCEPROP 2 LAST CDS_LIB pure_quanta
J 0
(1175 1500);
PAINT MONO (1175 1500);
DISPLAY INVISIBLE (1175 1500);
FORCEPROP 2 LAST CDS_LOCATION C1016
J 0
(1225 1700);
DISPLAY 1.021277 (1225 1700);
DISPLAY INVISIBLE (1225 1700);
FORCEPROP 2 LAST $SEC 1
J 0
(1225 1700);
DISPLAY 0.680851 (1225 1700);
PAINT MONO (1225 1700);
DISPLAY INVISIBLE (1225 1700);
FORCEPROP 2 LAST CDS_SEC 1
J 0
(1225 1700);
DISPLAY 1.021277 (1225 1700);
DISPLAY INVISIBLE (1225 1700);
FORCEPROP 1 LAST PATH I111
J 0
(1225 1650);
DISPLAY 0.978723 (1225 1650);
PAINT WHITE (1225 1650);
DISPLAY INVISIBLE (1225 1650);
FORCEADD Q_CAP..1
(1625 1500);
FORCEPROP 1 LAST PART_NUMBER CH622KMEB01
J 0
(1675 1350);
DISPLAY 0.638298 (1675 1350);
DISPLAY INVISIBLE (1675 1350);
FORCEPROP 1 LAST PACK_TYPE C0402
J 0
(1675 1300);
DISPLAY 0.638298 (1675 1300);
FORCEPROP 1 LAST MATERIAL X6S
J 0
(1675 1400);
DISPLAY 0.638298 (1675 1400);
FORCEPROP 1 LAST VALUE 22UF
J 0
(1675 1550);
DISPLAY 0.638298 (1675 1550);
FORCEPROP 1 LAST VOLTAGE 4V
J 0
(1675 1500);
DISPLAY 0.638298 (1675 1500);
FORCEPROP 1 LAST TOLERANCE 20%
J 0
(1675 1450);
DISPLAY 0.638298 (1675 1450);
FORCEPROP 1 LAST $LOCATION C1020
J 0
(1675 1600);
DISPLAY 0.638298 (1675 1600);
FORCEPROP 1 LASTPIN (1625 1600) $PN 1
J 0
(1635 1580);
DISPLAY 0.787234 (1635 1580);
FORCEPROP 1 LASTPIN (1625 1400) $PN 2
J 0
(1635 1380);
DISPLAY 0.787234 (1635 1380);
FORCEPROP 2 LAST CDS_LIB pure_quanta
J 0
(1625 1500);
PAINT MONO (1625 1500);
DISPLAY INVISIBLE (1625 1500);
FORCEPROP 2 LAST CDS_LOCATION C1020
J 0
(1675 1700);
DISPLAY 1.021277 (1675 1700);
DISPLAY INVISIBLE (1675 1700);
FORCEPROP 2 LAST $SEC 1
J 0
(1675 1700);
DISPLAY 0.680851 (1675 1700);
PAINT MONO (1675 1700);
DISPLAY INVISIBLE (1675 1700);
FORCEPROP 2 LAST CDS_SEC 1
J 0
(1675 1700);
DISPLAY 1.021277 (1675 1700);
DISPLAY INVISIBLE (1675 1700);
FORCEPROP 1 LAST PATH I112
J 0
(1675 1650);
DISPLAY 0.978723 (1675 1650);
PAINT WHITE (1675 1650);
DISPLAY INVISIBLE (1675 1650);
FORCEADD Q_CAP..1
(1150 2250);
FORCEPROP 1 LAST PART_NUMBER CH622KMEB01
J 0
(1200 2100);
DISPLAY 0.638298 (1200 2100);
DISPLAY INVISIBLE (1200 2100);
FORCEPROP 1 LAST PACK_TYPE C0402
J 0
(1200 2050);
DISPLAY 0.638298 (1200 2050);
FORCEPROP 1 LAST VALUE 22UF
J 0
(1200 2300);
DISPLAY 0.638298 (1200 2300);
FORCEPROP 1 LAST MATERIAL X6S
J 0
(1200 2150);
DISPLAY 0.638298 (1200 2150);
FORCEPROP 1 LAST VOLTAGE 4V
J 0
(1200 2250);
DISPLAY 0.638298 (1200 2250);
FORCEPROP 1 LAST TOLERANCE 20%
J 0
(1200 2200);
DISPLAY 0.638298 (1200 2200);
FORCEPROP 1 LAST $LOCATION C1015
J 0
(1200 2350);
DISPLAY 0.638298 (1200 2350);
FORCEPROP 1 LASTPIN (1150 2350) $PN 1
J 0
(1160 2330);
DISPLAY 0.787234 (1160 2330);
FORCEPROP 1 LASTPIN (1150 2150) $PN 2
J 0
(1160 2130);
DISPLAY 0.787234 (1160 2130);
FORCEPROP 2 LAST CDS_LIB pure_quanta
J 0
(1150 2250);
PAINT MONO (1150 2250);
DISPLAY INVISIBLE (1150 2250);
FORCEPROP 2 LAST CDS_LOCATION C1015
J 0
(1200 2450);
DISPLAY 1.021277 (1200 2450);
DISPLAY INVISIBLE (1200 2450);
FORCEPROP 2 LAST $SEC 1
J 0
(1200 2450);
DISPLAY 0.680851 (1200 2450);
PAINT MONO (1200 2450);
DISPLAY INVISIBLE (1200 2450);
FORCEPROP 2 LAST CDS_SEC 1
J 0
(1200 2450);
DISPLAY 1.021277 (1200 2450);
DISPLAY INVISIBLE (1200 2450);
FORCEPROP 1 LAST PATH I113
J 0
(1200 2400);
DISPLAY 0.978723 (1200 2400);
PAINT WHITE (1200 2400);
DISPLAY INVISIBLE (1200 2400);
FORCEADD Q_CAP..1
(1150 3025);
FORCEPROP 1 LAST PART_NUMBER CH622KMEB01
J 0
(1200 2875);
DISPLAY 0.638298 (1200 2875);
DISPLAY INVISIBLE (1200 2875);
FORCEPROP 1 LAST PACK_TYPE C0402
J 0
(1200 2825);
DISPLAY 0.638298 (1200 2825);
FORCEPROP 1 LAST MATERIAL X6S
J 0
(1200 2925);
DISPLAY 0.638298 (1200 2925);
FORCEPROP 1 LAST VOLTAGE 4V
J 0
(1200 3025);
DISPLAY 0.638298 (1200 3025);
FORCEPROP 1 LAST VALUE 22UF
J 0
(1200 3075);
DISPLAY 0.638298 (1200 3075);
FORCEPROP 1 LAST TOLERANCE 20%
J 0
(1200 2975);
DISPLAY 0.638298 (1200 2975);
FORCEPROP 1 LAST $LOCATION C1014
J 0
(1200 3125);
DISPLAY 0.638298 (1200 3125);
FORCEPROP 1 LASTPIN (1150 3125) $PN 1
J 0
(1160 3105);
DISPLAY 0.787234 (1160 3105);
FORCEPROP 1 LASTPIN (1150 2925) $PN 2
J 0
(1160 2905);
DISPLAY 0.787234 (1160 2905);
FORCEPROP 2 LAST CDS_LIB pure_quanta
J 0
(1150 3025);
PAINT MONO (1150 3025);
DISPLAY INVISIBLE (1150 3025);
FORCEPROP 2 LAST CDS_LOCATION C1014
J 0
(1200 3225);
DISPLAY 1.021277 (1200 3225);
DISPLAY INVISIBLE (1200 3225);
FORCEPROP 2 LAST $SEC 1
J 0
(1200 3225);
DISPLAY 0.680851 (1200 3225);
PAINT MONO (1200 3225);
DISPLAY INVISIBLE (1200 3225);
FORCEPROP 2 LAST CDS_SEC 1
J 0
(1200 3225);
DISPLAY 1.021277 (1200 3225);
DISPLAY INVISIBLE (1200 3225);
FORCEPROP 1 LAST PATH I114
J 0
(1200 3175);
DISPLAY 0.978723 (1200 3175);
PAINT WHITE (1200 3175);
DISPLAY INVISIBLE (1200 3175);
FORCEADD Q_CAP..1
(1600 2250);
FORCEPROP 1 LAST PART_NUMBER CH622KMEB01
J 0
(1650 2100);
DISPLAY 0.638298 (1650 2100);
DISPLAY INVISIBLE (1650 2100);
FORCEPROP 1 LAST PACK_TYPE C0402
J 0
(1650 2050);
DISPLAY 0.638298 (1650 2050);
FORCEPROP 1 LAST VALUE 22UF
J 0
(1650 2300);
DISPLAY 0.638298 (1650 2300);
FORCEPROP 1 LAST MATERIAL X6S
J 0
(1650 2150);
DISPLAY 0.638298 (1650 2150);
FORCEPROP 1 LAST VOLTAGE 4V
J 0
(1650 2250);
DISPLAY 0.638298 (1650 2250);
FORCEPROP 1 LAST TOLERANCE 20%
J 0
(1650 2200);
DISPLAY 0.638298 (1650 2200);
FORCEPROP 1 LAST $LOCATION C1019
J 0
(1650 2350);
DISPLAY 0.638298 (1650 2350);
FORCEPROP 1 LASTPIN (1600 2350) $PN 1
J 0
(1610 2330);
DISPLAY 0.787234 (1610 2330);
FORCEPROP 1 LASTPIN (1600 2150) $PN 2
J 0
(1610 2130);
DISPLAY 0.787234 (1610 2130);
FORCEPROP 2 LAST CDS_LIB pure_quanta
J 0
(1600 2250);
PAINT MONO (1600 2250);
DISPLAY INVISIBLE (1600 2250);
FORCEPROP 2 LAST CDS_LOCATION C1019
J 0
(1650 2450);
DISPLAY 1.021277 (1650 2450);
DISPLAY INVISIBLE (1650 2450);
FORCEPROP 2 LAST $SEC 1
J 0
(1650 2450);
DISPLAY 0.680851 (1650 2450);
PAINT MONO (1650 2450);
DISPLAY INVISIBLE (1650 2450);
FORCEPROP 2 LAST CDS_SEC 1
J 0
(1650 2450);
DISPLAY 1.021277 (1650 2450);
DISPLAY INVISIBLE (1650 2450);
FORCEPROP 1 LAST PATH I115
J 0
(1650 2400);
DISPLAY 0.978723 (1650 2400);
PAINT WHITE (1650 2400);
DISPLAY INVISIBLE (1650 2400);
FORCEADD Q_CAP..1
(1600 3025);
FORCEPROP 1 LAST PART_NUMBER CH622KMEB01
J 0
(1650 2875);
DISPLAY 0.638298 (1650 2875);
DISPLAY INVISIBLE (1650 2875);
FORCEPROP 1 LAST PACK_TYPE C0402
J 0
(1650 2825);
DISPLAY 0.638298 (1650 2825);
FORCEPROP 1 LAST MATERIAL X6S
J 0
(1650 2925);
DISPLAY 0.638298 (1650 2925);
FORCEPROP 1 LAST VOLTAGE 4V
J 0
(1650 3025);
DISPLAY 0.638298 (1650 3025);
FORCEPROP 1 LAST TOLERANCE 20%
J 0
(1650 2975);
DISPLAY 0.638298 (1650 2975);
FORCEPROP 1 LAST VALUE 22UF
J 0
(1650 3075);
DISPLAY 0.638298 (1650 3075);
FORCEPROP 1 LAST $LOCATION C1018
J 0
(1650 3125);
DISPLAY 0.638298 (1650 3125);
FORCEPROP 1 LASTPIN (1600 3125) $PN 1
J 0
(1610 3105);
DISPLAY 0.787234 (1610 3105);
FORCEPROP 1 LASTPIN (1600 2925) $PN 2
J 0
(1610 2905);
DISPLAY 0.787234 (1610 2905);
FORCEPROP 2 LAST CDS_LIB pure_quanta
J 0
(1600 3025);
PAINT MONO (1600 3025);
DISPLAY INVISIBLE (1600 3025);
FORCEPROP 2 LAST CDS_LOCATION C1018
J 0
(1650 3225);
DISPLAY 1.021277 (1650 3225);
DISPLAY INVISIBLE (1650 3225);
FORCEPROP 2 LAST $SEC 1
J 0
(1650 3225);
DISPLAY 0.680851 (1650 3225);
PAINT MONO (1650 3225);
DISPLAY INVISIBLE (1650 3225);
FORCEPROP 2 LAST CDS_SEC 1
J 0
(1650 3225);
DISPLAY 1.021277 (1650 3225);
DISPLAY INVISIBLE (1650 3225);
FORCEPROP 1 LAST PATH I116
J 0
(1650 3175);
DISPLAY 0.978723 (1650 3175);
PAINT WHITE (1650 3175);
DISPLAY INVISIBLE (1650 3175);
FORCEADD Q_CAP..1
(2075 1500);
FORCEPROP 1 LAST PART_NUMBER CH622KMEB01
J 0
(2125 1350);
DISPLAY 0.638298 (2125 1350);
DISPLAY INVISIBLE (2125 1350);
FORCEPROP 1 LAST PACK_TYPE C0402
J 0
(2125 1300);
DISPLAY 0.638298 (2125 1300);
FORCEPROP 1 LAST MATERIAL X6S
J 0
(2125 1400);
DISPLAY 0.638298 (2125 1400);
FORCEPROP 1 LAST VOLTAGE 4V
J 0
(2125 1500);
DISPLAY 0.638298 (2125 1500);
FORCEPROP 1 LAST VALUE 22UF
J 0
(2125 1550);
DISPLAY 0.638298 (2125 1550);
FORCEPROP 1 LAST TOLERANCE 20%
J 0
(2125 1450);
DISPLAY 0.638298 (2125 1450);
FORCEPROP 1 LAST $LOCATION C1024
J 0
(2125 1600);
DISPLAY 0.638298 (2125 1600);
FORCEPROP 1 LASTPIN (2075 1600) $PN 1
J 0
(2085 1580);
DISPLAY 0.787234 (2085 1580);
FORCEPROP 1 LASTPIN (2075 1400) $PN 2
J 0
(2085 1380);
DISPLAY 0.787234 (2085 1380);
FORCEPROP 2 LAST CDS_LIB pure_quanta
J 0
(2075 1500);
PAINT MONO (2075 1500);
DISPLAY INVISIBLE (2075 1500);
FORCEPROP 2 LAST CDS_LOCATION C1024
J 0
(2125 1700);
DISPLAY 1.021277 (2125 1700);
DISPLAY INVISIBLE (2125 1700);
FORCEPROP 2 LAST $SEC 1
J 0
(2125 1700);
DISPLAY 0.680851 (2125 1700);
PAINT MONO (2125 1700);
DISPLAY INVISIBLE (2125 1700);
FORCEPROP 2 LAST CDS_SEC 1
J 0
(2125 1700);
DISPLAY 1.021277 (2125 1700);
DISPLAY INVISIBLE (2125 1700);
FORCEPROP 1 LAST PATH I117
J 0
(2125 1650);
DISPLAY 0.978723 (2125 1650);
PAINT WHITE (2125 1650);
DISPLAY INVISIBLE (2125 1650);
FORCEADD Q_CAP..1
(2525 1500);
FORCEPROP 1 LAST PART_NUMBER CH622KMEB01
J 0
(2575 1350);
DISPLAY 0.638298 (2575 1350);
DISPLAY INVISIBLE (2575 1350);
FORCEPROP 1 LAST MATERIAL X6S
J 0
(2575 1400);
DISPLAY 0.638298 (2575 1400);
FORCEPROP 1 LAST PACK_TYPE C0402
J 0
(2575 1300);
DISPLAY 0.638298 (2575 1300);
FORCEPROP 1 LAST TOLERANCE 20%
J 0
(2575 1450);
DISPLAY 0.638298 (2575 1450);
FORCEPROP 1 LAST VALUE 22UF
J 0
(2575 1550);
DISPLAY 0.638298 (2575 1550);
FORCEPROP 1 LAST VOLTAGE 4V
J 0
(2575 1500);
DISPLAY 0.638298 (2575 1500);
FORCEPROP 1 LAST $LOCATION C1028
J 0
(2575 1600);
DISPLAY 0.638298 (2575 1600);
FORCEPROP 1 LASTPIN (2525 1600) $PN 1
J 0
(2535 1580);
DISPLAY 0.787234 (2535 1580);
FORCEPROP 1 LASTPIN (2525 1400) $PN 2
J 0
(2535 1380);
DISPLAY 0.787234 (2535 1380);
FORCEPROP 2 LAST CDS_LIB pure_quanta
J 0
(2525 1500);
PAINT MONO (2525 1500);
DISPLAY INVISIBLE (2525 1500);
FORCEPROP 2 LAST CDS_LOCATION C1028
J 0
(2575 1700);
DISPLAY 1.021277 (2575 1700);
DISPLAY INVISIBLE (2575 1700);
FORCEPROP 2 LAST $SEC 1
J 0
(2575 1700);
DISPLAY 0.680851 (2575 1700);
PAINT MONO (2575 1700);
DISPLAY INVISIBLE (2575 1700);
FORCEPROP 2 LAST CDS_SEC 1
J 0
(2575 1700);
DISPLAY 1.021277 (2575 1700);
DISPLAY INVISIBLE (2575 1700);
FORCEPROP 1 LAST PATH I118
J 0
(2575 1650);
DISPLAY 0.978723 (2575 1650);
PAINT WHITE (2575 1650);
DISPLAY INVISIBLE (2575 1650);
FORCEADD Q_CAP..1
(2975 1500);
FORCEPROP 1 LAST PART_NUMBER CH622KMEB01
J 0
(3025 1350);
DISPLAY 0.638298 (3025 1350);
DISPLAY INVISIBLE (3025 1350);
FORCEPROP 1 LAST MATERIAL X6S
J 0
(3025 1400);
DISPLAY 0.638298 (3025 1400);
FORCEPROP 1 LAST PACK_TYPE C0402
J 0
(3025 1300);
DISPLAY 0.638298 (3025 1300);
FORCEPROP 1 LAST TOLERANCE 20%
J 0
(3025 1450);
DISPLAY 0.638298 (3025 1450);
FORCEPROP 1 LAST VALUE 22UF
J 0
(3025 1550);
DISPLAY 0.638298 (3025 1550);
FORCEPROP 1 LAST VOLTAGE 4V
J 0
(3025 1500);
DISPLAY 0.638298 (3025 1500);
FORCEPROP 1 LAST $LOCATION C1032
J 0
(3025 1600);
DISPLAY 0.638298 (3025 1600);
FORCEPROP 1 LASTPIN (2975 1600) $PN 1
J 0
(2985 1580);
DISPLAY 0.787234 (2985 1580);
FORCEPROP 1 LASTPIN (2975 1400) $PN 2
J 0
(2985 1380);
DISPLAY 0.787234 (2985 1380);
FORCEPROP 2 LAST CDS_LIB pure_quanta
J 0
(2975 1500);
PAINT MONO (2975 1500);
DISPLAY INVISIBLE (2975 1500);
FORCEPROP 2 LAST CDS_LOCATION C1032
J 0
(3025 1700);
DISPLAY 1.021277 (3025 1700);
DISPLAY INVISIBLE (3025 1700);
FORCEPROP 2 LAST $SEC 1
J 0
(3025 1700);
DISPLAY 0.680851 (3025 1700);
PAINT MONO (3025 1700);
DISPLAY INVISIBLE (3025 1700);
FORCEPROP 2 LAST CDS_SEC 1
J 0
(3025 1700);
DISPLAY 1.021277 (3025 1700);
DISPLAY INVISIBLE (3025 1700);
FORCEPROP 1 LAST PATH I119
J 0
(3025 1650);
DISPLAY 0.978723 (3025 1650);
PAINT WHITE (3025 1650);
DISPLAY INVISIBLE (3025 1650);
FORCEADD UNIVERSAL_POWER..1
(-4250 -575);
FORCEPROP 3 LASTPIN (-4250 -625) SIG_NAME PVCCD_HV_CPU0\g
J 0
(-4240 -615);
DISPLAY 0.659574 (-4240 -615);
PAINT MONO (-4240 -615);
DISPLAY INVISIBLE (-4240 -615);
FORCEPROP 1 LAST HDL_POWER PVCCD_HV_CPU0
J 1
(-4025 -525);
DISPLAY 0.872340 (-4025 -525);
PAINT GREEN (-4025 -525);
FORCEPROP 2 LAST CDS_LIB logical_power
J 0
(-4250 -575);
PAINT MONO (-4250 -575);
DISPLAY INVISIBLE (-4250 -575);
FORCEPROP 1 LAST PATH I12
J 0
(-4200 -550);
DISPLAY 0.872340 (-4200 -550);
PAINT AQUA (-4200 -550);
DISPLAY INVISIBLE (-4200 -550);
FORCEADD Q_CAP..1
(2050 2250);
FORCEPROP 1 LAST PART_NUMBER CH622KMEB01
J 0
(2100 2100);
DISPLAY 0.638298 (2100 2100);
DISPLAY INVISIBLE (2100 2100);
FORCEPROP 1 LAST MATERIAL X6S
J 0
(2100 2150);
DISPLAY 0.638298 (2100 2150);
FORCEPROP 1 LAST PACK_TYPE C0402
J 0
(2100 2050);
DISPLAY 0.638298 (2100 2050);
FORCEPROP 1 LAST VALUE 22UF
J 0
(2100 2300);
DISPLAY 0.638298 (2100 2300);
FORCEPROP 1 LAST TOLERANCE 20%
J 0
(2100 2200);
DISPLAY 0.638298 (2100 2200);
FORCEPROP 1 LAST VOLTAGE 4V
J 0
(2100 2250);
DISPLAY 0.638298 (2100 2250);
FORCEPROP 1 LAST $LOCATION C1023
J 0
(2100 2350);
DISPLAY 0.638298 (2100 2350);
FORCEPROP 1 LASTPIN (2050 2350) $PN 1
J 0
(2060 2330);
DISPLAY 0.787234 (2060 2330);
FORCEPROP 1 LASTPIN (2050 2150) $PN 2
J 0
(2060 2130);
DISPLAY 0.787234 (2060 2130);
FORCEPROP 2 LAST CDS_LIB pure_quanta
J 0
(2050 2250);
PAINT MONO (2050 2250);
DISPLAY INVISIBLE (2050 2250);
FORCEPROP 2 LAST CDS_LOCATION C1023
J 0
(2100 2450);
DISPLAY 1.021277 (2100 2450);
DISPLAY INVISIBLE (2100 2450);
FORCEPROP 2 LAST $SEC 1
J 0
(2100 2450);
DISPLAY 0.680851 (2100 2450);
PAINT MONO (2100 2450);
DISPLAY INVISIBLE (2100 2450);
FORCEPROP 2 LAST CDS_SEC 1
J 0
(2100 2450);
DISPLAY 1.021277 (2100 2450);
DISPLAY INVISIBLE (2100 2450);
FORCEPROP 1 LAST PATH I120
J 0
(2100 2400);
DISPLAY 0.978723 (2100 2400);
PAINT WHITE (2100 2400);
DISPLAY INVISIBLE (2100 2400);
FORCEADD Q_CAP..1
(2500 2250);
FORCEPROP 1 LAST PART_NUMBER CH622KMEB01
J 0
(2550 2100);
DISPLAY 0.638298 (2550 2100);
DISPLAY INVISIBLE (2550 2100);
FORCEPROP 1 LAST VALUE 22UF
J 0
(2550 2300);
DISPLAY 0.638298 (2550 2300);
FORCEPROP 1 LAST PACK_TYPE C0402
J 0
(2550 2050);
DISPLAY 0.638298 (2550 2050);
FORCEPROP 1 LAST MATERIAL X6S
J 0
(2550 2150);
DISPLAY 0.638298 (2550 2150);
FORCEPROP 1 LAST VOLTAGE 4V
J 0
(2550 2250);
DISPLAY 0.638298 (2550 2250);
FORCEPROP 1 LAST TOLERANCE 20%
J 0
(2550 2200);
DISPLAY 0.638298 (2550 2200);
FORCEPROP 1 LAST $LOCATION C1027
J 0
(2550 2350);
DISPLAY 0.638298 (2550 2350);
FORCEPROP 1 LASTPIN (2500 2350) $PN 1
J 0
(2510 2330);
DISPLAY 0.787234 (2510 2330);
FORCEPROP 1 LASTPIN (2500 2150) $PN 2
J 0
(2510 2130);
DISPLAY 0.787234 (2510 2130);
FORCEPROP 2 LAST CDS_LIB pure_quanta
J 0
(2500 2250);
PAINT MONO (2500 2250);
DISPLAY INVISIBLE (2500 2250);
FORCEPROP 2 LAST CDS_LOCATION C1027
J 0
(2550 2450);
DISPLAY 1.021277 (2550 2450);
DISPLAY INVISIBLE (2550 2450);
FORCEPROP 2 LAST $SEC 1
J 0
(2550 2450);
DISPLAY 0.680851 (2550 2450);
PAINT MONO (2550 2450);
DISPLAY INVISIBLE (2550 2450);
FORCEPROP 2 LAST CDS_SEC 1
J 0
(2550 2450);
DISPLAY 1.021277 (2550 2450);
DISPLAY INVISIBLE (2550 2450);
FORCEPROP 1 LAST PATH I121
J 0
(2550 2400);
DISPLAY 0.978723 (2550 2400);
PAINT WHITE (2550 2400);
DISPLAY INVISIBLE (2550 2400);
FORCEADD Q_CAP..1
(2050 3025);
FORCEPROP 1 LAST PART_NUMBER CH622KMEB01
J 0
(2100 2875);
DISPLAY 0.638298 (2100 2875);
DISPLAY INVISIBLE (2100 2875);
FORCEPROP 1 LAST MATERIAL X6S
J 0
(2100 2925);
DISPLAY 0.638298 (2100 2925);
FORCEPROP 1 LAST PACK_TYPE C0402
J 0
(2100 2825);
DISPLAY 0.638298 (2100 2825);
FORCEPROP 1 LAST TOLERANCE 20%
J 0
(2100 2975);
DISPLAY 0.638298 (2100 2975);
FORCEPROP 1 LAST VOLTAGE 4V
J 0
(2100 3025);
DISPLAY 0.638298 (2100 3025);
FORCEPROP 1 LAST VALUE 22UF
J 0
(2100 3075);
DISPLAY 0.638298 (2100 3075);
FORCEPROP 1 LAST $LOCATION C1022
J 0
(2100 3125);
DISPLAY 0.638298 (2100 3125);
FORCEPROP 1 LASTPIN (2050 3125) $PN 1
J 0
(2060 3105);
DISPLAY 0.787234 (2060 3105);
FORCEPROP 1 LASTPIN (2050 2925) $PN 2
J 0
(2060 2905);
DISPLAY 0.787234 (2060 2905);
FORCEPROP 2 LAST CDS_LIB pure_quanta
J 0
(2050 3025);
PAINT MONO (2050 3025);
DISPLAY INVISIBLE (2050 3025);
FORCEPROP 2 LAST CDS_LOCATION C1022
J 0
(2100 3225);
DISPLAY 1.021277 (2100 3225);
DISPLAY INVISIBLE (2100 3225);
FORCEPROP 2 LAST $SEC 1
J 0
(2100 3225);
DISPLAY 0.680851 (2100 3225);
PAINT MONO (2100 3225);
DISPLAY INVISIBLE (2100 3225);
FORCEPROP 2 LAST CDS_SEC 1
J 0
(2100 3225);
DISPLAY 1.021277 (2100 3225);
DISPLAY INVISIBLE (2100 3225);
FORCEPROP 1 LAST PATH I122
J 0
(2100 3175);
DISPLAY 0.978723 (2100 3175);
PAINT WHITE (2100 3175);
DISPLAY INVISIBLE (2100 3175);
FORCEADD Q_CAP..1
(2500 3025);
FORCEPROP 1 LAST PART_NUMBER CH622KMEB01
J 0
(2550 2875);
DISPLAY 0.638298 (2550 2875);
DISPLAY INVISIBLE (2550 2875);
FORCEPROP 1 LAST MATERIAL X6S
J 0
(2550 2925);
DISPLAY 0.638298 (2550 2925);
FORCEPROP 1 LAST PACK_TYPE C0402
J 0
(2550 2825);
DISPLAY 0.638298 (2550 2825);
FORCEPROP 1 LAST TOLERANCE 20%
J 0
(2550 2975);
DISPLAY 0.638298 (2550 2975);
FORCEPROP 1 LAST VALUE 22UF
J 0
(2550 3075);
DISPLAY 0.638298 (2550 3075);
FORCEPROP 1 LAST VOLTAGE 4V
J 0
(2550 3025);
DISPLAY 0.638298 (2550 3025);
FORCEPROP 1 LAST $LOCATION C1026
J 0
(2550 3125);
DISPLAY 0.638298 (2550 3125);
FORCEPROP 1 LASTPIN (2500 3125) $PN 1
J 0
(2510 3105);
DISPLAY 0.787234 (2510 3105);
FORCEPROP 1 LASTPIN (2500 2925) $PN 2
J 0
(2510 2905);
DISPLAY 0.787234 (2510 2905);
FORCEPROP 2 LAST CDS_LIB pure_quanta
J 0
(2500 3025);
PAINT MONO (2500 3025);
DISPLAY INVISIBLE (2500 3025);
FORCEPROP 2 LAST CDS_LOCATION C1026
J 0
(2550 3225);
DISPLAY 1.021277 (2550 3225);
DISPLAY INVISIBLE (2550 3225);
FORCEPROP 2 LAST $SEC 1
J 0
(2550 3225);
DISPLAY 0.680851 (2550 3225);
PAINT MONO (2550 3225);
DISPLAY INVISIBLE (2550 3225);
FORCEPROP 2 LAST CDS_SEC 1
J 0
(2550 3225);
DISPLAY 1.021277 (2550 3225);
DISPLAY INVISIBLE (2550 3225);
FORCEPROP 1 LAST PATH I123
J 0
(2550 3175);
DISPLAY 0.978723 (2550 3175);
PAINT WHITE (2550 3175);
DISPLAY INVISIBLE (2550 3175);
FORCEADD Q_CAP..1
(2950 2250);
FORCEPROP 1 LAST PART_NUMBER CH622KMEB01
J 0
(3000 2100);
DISPLAY 0.638298 (3000 2100);
DISPLAY INVISIBLE (3000 2100);
FORCEPROP 1 LAST VALUE 22UF
J 0
(3000 2300);
DISPLAY 0.638298 (3000 2300);
FORCEPROP 1 LAST PACK_TYPE C0402
J 0
(3000 2050);
DISPLAY 0.638298 (3000 2050);
FORCEPROP 1 LAST MATERIAL X6S
J 0
(3000 2150);
DISPLAY 0.638298 (3000 2150);
FORCEPROP 1 LAST VOLTAGE 4V
J 0
(3000 2250);
DISPLAY 0.638298 (3000 2250);
FORCEPROP 1 LAST TOLERANCE 20%
J 0
(3000 2200);
DISPLAY 0.638298 (3000 2200);
FORCEPROP 1 LAST $LOCATION C1031
J 0
(3000 2350);
DISPLAY 0.638298 (3000 2350);
FORCEPROP 1 LASTPIN (2950 2350) $PN 1
J 0
(2960 2330);
DISPLAY 0.787234 (2960 2330);
FORCEPROP 1 LASTPIN (2950 2150) $PN 2
J 0
(2960 2130);
DISPLAY 0.787234 (2960 2130);
FORCEPROP 2 LAST CDS_LIB pure_quanta
J 0
(2950 2250);
PAINT MONO (2950 2250);
DISPLAY INVISIBLE (2950 2250);
FORCEPROP 2 LAST CDS_LOCATION C1031
J 0
(3000 2450);
DISPLAY 1.021277 (3000 2450);
DISPLAY INVISIBLE (3000 2450);
FORCEPROP 2 LAST $SEC 1
J 0
(3000 2450);
DISPLAY 0.680851 (3000 2450);
PAINT MONO (3000 2450);
DISPLAY INVISIBLE (3000 2450);
FORCEPROP 2 LAST CDS_SEC 1
J 0
(3000 2450);
DISPLAY 1.021277 (3000 2450);
DISPLAY INVISIBLE (3000 2450);
FORCEPROP 1 LAST PATH I124
J 0
(3000 2400);
DISPLAY 0.978723 (3000 2400);
PAINT WHITE (3000 2400);
DISPLAY INVISIBLE (3000 2400);
FORCEADD Q_CAP..1
(2950 3025);
FORCEPROP 1 LAST PART_NUMBER CH622KMEB01
J 0
(3000 2875);
DISPLAY 0.638298 (3000 2875);
DISPLAY INVISIBLE (3000 2875);
FORCEPROP 1 LAST PACK_TYPE C0402
J 0
(3000 2825);
DISPLAY 0.638298 (3000 2825);
FORCEPROP 1 LAST MATERIAL X6S
J 0
(3000 2925);
DISPLAY 0.638298 (3000 2925);
FORCEPROP 1 LAST VALUE 22UF
J 0
(3000 3075);
DISPLAY 0.638298 (3000 3075);
FORCEPROP 1 LAST TOLERANCE 20%
J 0
(3000 2975);
DISPLAY 0.638298 (3000 2975);
FORCEPROP 1 LAST VOLTAGE 4V
J 0
(3000 3025);
DISPLAY 0.638298 (3000 3025);
FORCEPROP 1 LAST $LOCATION C1030
J 0
(3000 3125);
DISPLAY 0.638298 (3000 3125);
FORCEPROP 1 LASTPIN (2950 3125) $PN 1
J 0
(2960 3105);
DISPLAY 0.787234 (2960 3105);
FORCEPROP 1 LASTPIN (2950 2925) $PN 2
J 0
(2960 2905);
DISPLAY 0.787234 (2960 2905);
FORCEPROP 2 LAST CDS_LIB pure_quanta
J 0
(2950 3025);
PAINT MONO (2950 3025);
DISPLAY INVISIBLE (2950 3025);
FORCEPROP 2 LAST CDS_LOCATION C1030
J 0
(3000 3225);
DISPLAY 1.021277 (3000 3225);
DISPLAY INVISIBLE (3000 3225);
FORCEPROP 2 LAST $SEC 1
J 0
(3000 3225);
DISPLAY 0.680851 (3000 3225);
PAINT MONO (3000 3225);
DISPLAY INVISIBLE (3000 3225);
FORCEPROP 2 LAST CDS_SEC 1
J 0
(3000 3225);
DISPLAY 1.021277 (3000 3225);
DISPLAY INVISIBLE (3000 3225);
FORCEPROP 1 LAST PATH I125
J 0
(3000 3175);
DISPLAY 0.978723 (3000 3175);
PAINT WHITE (3000 3175);
DISPLAY INVISIBLE (3000 3175);
FORCEADD UNIVERSAL_POWER..1
(250 3300);
FORCEPROP 3 LASTPIN (250 3250) SIG_NAME PVCCIN_CPU0\g
J 0
(260 3260);
DISPLAY 0.659574 (260 3260);
PAINT MONO (260 3260);
DISPLAY INVISIBLE (260 3260);
FORCEPROP 1 LAST HDL_POWER PVCCIN_CPU0
J 1
(450 3350);
DISPLAY 0.872340 (450 3350);
PAINT GREEN (450 3350);
FORCEPROP 2 LAST CDS_LIB logical_power
J 0
(250 3300);
DISPLAY INVISIBLE (250 3300);
FORCEPROP 1 LAST PATH I126
J 0
(300 3325);
DISPLAY 0.872340 (300 3325);
PAINT AQUA (300 3325);
DISPLAY INVISIBLE (300 3325);
FORCEADD Q_CAP..1
(3425 725);
FORCEPROP 1 LAST PART_NUMBER CH622KMEB01
J 0
(3475 575);
DISPLAY 0.638298 (3475 575);
DISPLAY INVISIBLE (3475 575);
FORCEPROP 1 LAST PACK_TYPE C0402
J 0
(3475 525);
DISPLAY 0.638298 (3475 525);
FORCEPROP 1 LAST TOLERANCE 20%
J 0
(3475 675);
DISPLAY 0.638298 (3475 675);
FORCEPROP 1 LAST MATERIAL X6S
J 0
(3475 625);
DISPLAY 0.638298 (3475 625);
FORCEPROP 1 LAST VALUE 22UF
J 0
(3475 775);
DISPLAY 0.638298 (3475 775);
FORCEPROP 1 LAST VOLTAGE 4V
J 0
(3475 725);
DISPLAY 0.638298 (3475 725);
FORCEPROP 1 LAST $LOCATION C1037
J 0
(3475 825);
DISPLAY 0.638298 (3475 825);
FORCEPROP 1 LASTPIN (3425 825) $PN 1
J 0
(3435 805);
DISPLAY 0.787234 (3435 805);
FORCEPROP 1 LASTPIN (3425 625) $PN 2
J 0
(3435 605);
DISPLAY 0.787234 (3435 605);
FORCEPROP 2 LAST CDS_LIB pure_quanta
J 0
(3425 725);
PAINT MONO (3425 725);
DISPLAY INVISIBLE (3425 725);
FORCEPROP 2 LAST CDS_LOCATION C1037
J 0
(3475 925);
DISPLAY 1.021277 (3475 925);
DISPLAY INVISIBLE (3475 925);
FORCEPROP 2 LAST $SEC 1
J 0
(3475 925);
DISPLAY 0.680851 (3475 925);
PAINT MONO (3475 925);
DISPLAY INVISIBLE (3475 925);
FORCEPROP 2 LAST CDS_SEC 1
J 0
(3475 925);
DISPLAY 1.021277 (3475 925);
DISPLAY INVISIBLE (3475 925);
FORCEPROP 1 LAST PATH I127
J 0
(3475 875);
DISPLAY 0.978723 (3475 875);
PAINT WHITE (3475 875);
DISPLAY INVISIBLE (3475 875);
FORCEADD Q_CAP..1
(3875 725);
FORCEPROP 1 LAST PART_NUMBER CH622KMEB01
J 0
(3925 575);
DISPLAY 0.638298 (3925 575);
DISPLAY INVISIBLE (3925 575);
FORCEPROP 1 LAST PACK_TYPE C0402
J 0
(3925 525);
DISPLAY 0.638298 (3925 525);
FORCEPROP 1 LAST VALUE 22UF
J 0
(3925 775);
DISPLAY 0.638298 (3925 775);
FORCEPROP 1 LAST VOLTAGE 4V
J 0
(3925 725);
DISPLAY 0.638298 (3925 725);
FORCEPROP 1 LAST MATERIAL X6S
J 0
(3925 625);
DISPLAY 0.638298 (3925 625);
FORCEPROP 1 LAST TOLERANCE 20%
J 0
(3925 675);
DISPLAY 0.638298 (3925 675);
FORCEPROP 1 LAST $LOCATION C1041
J 0
(3925 825);
DISPLAY 0.638298 (3925 825);
FORCEPROP 1 LASTPIN (3875 825) $PN 1
J 0
(3885 805);
DISPLAY 0.787234 (3885 805);
FORCEPROP 1 LASTPIN (3875 625) $PN 2
J 0
(3885 605);
DISPLAY 0.787234 (3885 605);
FORCEPROP 2 LAST CDS_LIB pure_quanta
J 0
(3875 725);
PAINT MONO (3875 725);
DISPLAY INVISIBLE (3875 725);
FORCEPROP 2 LAST CDS_LOCATION C1041
J 0
(3925 925);
DISPLAY 1.021277 (3925 925);
DISPLAY INVISIBLE (3925 925);
FORCEPROP 2 LAST $SEC 1
J 0
(3925 925);
DISPLAY 0.680851 (3925 925);
PAINT MONO (3925 925);
DISPLAY INVISIBLE (3925 925);
FORCEPROP 2 LAST CDS_SEC 1
J 0
(3925 925);
DISPLAY 1.021277 (3925 925);
DISPLAY INVISIBLE (3925 925);
FORCEPROP 1 LAST PATH I128
J 0
(3925 875);
DISPLAY 0.978723 (3925 875);
PAINT WHITE (3925 875);
DISPLAY INVISIBLE (3925 875);
FORCEADD UNIVERSAL_GND..1
(4325 375);
FORCEPROP 3 LASTPIN (4325 425) SIG_NAME GND\g
J 0
(4335 435);
DISPLAY 0.659574 (4335 435);
PAINT MONO (4335 435);
DISPLAY INVISIBLE (4335 435);
FORCEPROP 2 LAST CDS_LIB logical_power
J 0
(4325 375);
PAINT MONO (4325 375);
DISPLAY INVISIBLE (4325 375);
FORCEPROP 1 LAST HDL_POWER GND
J 1
(4350 300);
DISPLAY 0.872340 (4350 300);
PAINT GREEN (4350 300);
DISPLAY INVISIBLE (4350 300);
FORCEPROP 1 LAST PATH I129
J 0
(4400 375);
DISPLAY 0.872340 (4400 375);
PAINT AQUA (4400 375);
DISPLAY INVISIBLE (4400 375);
FORCEADD Q_CAP..1
(-4250 -50);
FORCEPROP 1 LAST PART_NUMBER CH647KMEA04
J 0
(-4200 -200);
DISPLAY 0.638298 (-4200 -200);
DISPLAY INVISIBLE (-4200 -200);
FORCEPROP 1 LAST MATERIAL X6S
J 0
(-4200 -150);
DISPLAY 0.638298 (-4200 -150);
FORCEPROP 1 LAST PACK_TYPE C0805
J 0
(-4200 -250);
DISPLAY 0.638298 (-4200 -250);
FORCEPROP 1 LAST VOLTAGE 4V
J 0
(-4200 -50);
DISPLAY 0.638298 (-4200 -50);
FORCEPROP 1 LAST TOLERANCE 20%
J 0
(-4200 -100);
DISPLAY 0.638298 (-4200 -100);
FORCEPROP 1 LAST VALUE 47UF
J 0
(-4200 0);
DISPLAY 0.638298 (-4200 0);
FORCEPROP 1 LAST $LOCATION C101
J 0
(-4200 50);
DISPLAY 0.638298 (-4200 50);
FORCEPROP 1 LASTPIN (-4250 50) $PN 1
J 0
(-4240 30);
DISPLAY 0.787234 (-4240 30);
FORCEPROP 1 LASTPIN (-4250 -150) $PN 2
J 0
(-4240 -170);
DISPLAY 0.787234 (-4240 -170);
FORCEPROP 2 LAST CDS_LIB pure_quanta
J 0
(-4250 -50);
PAINT MONO (-4250 -50);
DISPLAY INVISIBLE (-4250 -50);
FORCEPROP 1 LAST $LOCATION C101
J 0
(-4200 150);
DISPLAY 1.021277 (-4200 150);
DISPLAY INVISIBLE (-4200 150);
FORCEPROP 2 LAST CDS_LOCATION C101
J 0
(-4200 150);
DISPLAY 1.021277 (-4200 150);
DISPLAY INVISIBLE (-4200 150);
FORCEPROP 2 LAST $SEC 1
J 0
(-4200 150);
DISPLAY 0.680851 (-4200 150);
PAINT MONO (-4200 150);
DISPLAY INVISIBLE (-4200 150);
FORCEPROP 2 LAST CDS_SEC 1
J 0
(-4200 150);
DISPLAY 1.021277 (-4200 150);
DISPLAY INVISIBLE (-4200 150);
FORCEPROP 1 LAST PATH I13
J 0
(-4200 100);
DISPLAY 0.978723 (-4200 100);
PAINT WHITE (-4200 100);
DISPLAY INVISIBLE (-4200 100);
FORCEADD Q_CAP..1
(4325 725);
FORCEPROP 1 LAST PART_NUMBER CH622KMEB01
J 0
(4375 575);
DISPLAY 0.638298 (4375 575);
DISPLAY INVISIBLE (4375 575);
FORCEPROP 1 LAST PACK_TYPE C0402
J 0
(4375 525);
DISPLAY 0.638298 (4375 525);
FORCEPROP 1 LAST VOLTAGE 4V
J 0
(4375 725);
DISPLAY 0.638298 (4375 725);
FORCEPROP 1 LAST VALUE 22UF
J 0
(4375 775);
DISPLAY 0.638298 (4375 775);
FORCEPROP 1 LAST MATERIAL X6S
J 0
(4375 625);
DISPLAY 0.638298 (4375 625);
FORCEPROP 1 LAST TOLERANCE 20%
J 0
(4375 675);
DISPLAY 0.638298 (4375 675);
FORCEPROP 1 LAST $LOCATION C1045
J 0
(4375 825);
DISPLAY 0.638298 (4375 825);
FORCEPROP 1 LASTPIN (4325 825) $PN 1
J 0
(4335 805);
DISPLAY 0.787234 (4335 805);
FORCEPROP 1 LASTPIN (4325 625) $PN 2
J 0
(4335 605);
DISPLAY 0.787234 (4335 605);
FORCEPROP 2 LAST CDS_LIB pure_quanta
J 0
(4325 725);
PAINT MONO (4325 725);
DISPLAY INVISIBLE (4325 725);
FORCEPROP 2 LAST CDS_LOCATION C1045
J 0
(4375 925);
DISPLAY 1.021277 (4375 925);
DISPLAY INVISIBLE (4375 925);
FORCEPROP 2 LAST $SEC 1
J 0
(4375 925);
DISPLAY 0.680851 (4375 925);
PAINT MONO (4375 925);
DISPLAY INVISIBLE (4375 925);
FORCEPROP 2 LAST CDS_SEC 1
J 0
(4375 925);
DISPLAY 1.021277 (4375 925);
DISPLAY INVISIBLE (4375 925);
FORCEPROP 1 LAST PATH I130
J 0
(4375 875);
DISPLAY 0.978723 (4375 875);
PAINT WHITE (4375 875);
DISPLAY INVISIBLE (4375 875);
FORCEADD Q_CAP..1
(3425 1500);
FORCEPROP 1 LAST PART_NUMBER CH622KMEB01
J 0
(3475 1350);
DISPLAY 0.638298 (3475 1350);
DISPLAY INVISIBLE (3475 1350);
FORCEPROP 1 LAST MATERIAL X6S
J 0
(3475 1400);
DISPLAY 0.638298 (3475 1400);
FORCEPROP 1 LAST PACK_TYPE C0402
J 0
(3475 1300);
DISPLAY 0.638298 (3475 1300);
FORCEPROP 1 LAST TOLERANCE 20%
J 0
(3475 1450);
DISPLAY 0.638298 (3475 1450);
FORCEPROP 1 LAST VALUE 22UF
J 0
(3475 1550);
DISPLAY 0.638298 (3475 1550);
FORCEPROP 1 LAST VOLTAGE 4V
J 0
(3475 1500);
DISPLAY 0.638298 (3475 1500);
FORCEPROP 1 LAST $LOCATION C1036
J 0
(3475 1600);
DISPLAY 0.638298 (3475 1600);
FORCEPROP 1 LASTPIN (3425 1600) $PN 1
J 0
(3435 1580);
DISPLAY 0.787234 (3435 1580);
FORCEPROP 1 LASTPIN (3425 1400) $PN 2
J 0
(3435 1380);
DISPLAY 0.787234 (3435 1380);
FORCEPROP 2 LAST CDS_LIB pure_quanta
J 0
(3425 1500);
PAINT MONO (3425 1500);
DISPLAY INVISIBLE (3425 1500);
FORCEPROP 2 LAST CDS_LOCATION C1036
J 0
(3475 1700);
DISPLAY 1.021277 (3475 1700);
DISPLAY INVISIBLE (3475 1700);
FORCEPROP 2 LAST $SEC 1
J 0
(3475 1700);
DISPLAY 0.680851 (3475 1700);
PAINT MONO (3475 1700);
DISPLAY INVISIBLE (3475 1700);
FORCEPROP 2 LAST CDS_SEC 1
J 0
(3475 1700);
DISPLAY 1.021277 (3475 1700);
DISPLAY INVISIBLE (3475 1700);
FORCEPROP 1 LAST PATH I131
J 0
(3475 1650);
DISPLAY 0.978723 (3475 1650);
PAINT WHITE (3475 1650);
DISPLAY INVISIBLE (3475 1650);
FORCEADD Q_CAP..1
(3875 1500);
FORCEPROP 1 LAST PART_NUMBER CH622KMEB01
J 0
(3925 1350);
DISPLAY 0.638298 (3925 1350);
DISPLAY INVISIBLE (3925 1350);
FORCEPROP 1 LAST MATERIAL X6S
J 0
(3925 1400);
DISPLAY 0.638298 (3925 1400);
FORCEPROP 1 LAST PACK_TYPE C0402
J 0
(3925 1300);
DISPLAY 0.638298 (3925 1300);
FORCEPROP 1 LAST VOLTAGE 4V
J 0
(3925 1500);
DISPLAY 0.638298 (3925 1500);
FORCEPROP 1 LAST VALUE 22UF
J 0
(3925 1550);
DISPLAY 0.638298 (3925 1550);
FORCEPROP 1 LAST TOLERANCE 20%
J 0
(3925 1450);
DISPLAY 0.638298 (3925 1450);
FORCEPROP 1 LAST $LOCATION C1040
J 0
(3925 1600);
DISPLAY 0.638298 (3925 1600);
FORCEPROP 1 LASTPIN (3875 1600) $PN 1
J 0
(3885 1580);
DISPLAY 0.787234 (3885 1580);
FORCEPROP 1 LASTPIN (3875 1400) $PN 2
J 0
(3885 1380);
DISPLAY 0.787234 (3885 1380);
FORCEPROP 2 LAST CDS_LIB pure_quanta
J 0
(3875 1500);
PAINT MONO (3875 1500);
DISPLAY INVISIBLE (3875 1500);
FORCEPROP 2 LAST CDS_LOCATION C1040
J 0
(3925 1700);
DISPLAY 1.021277 (3925 1700);
DISPLAY INVISIBLE (3925 1700);
FORCEPROP 2 LAST $SEC 1
J 0
(3925 1700);
DISPLAY 0.680851 (3925 1700);
PAINT MONO (3925 1700);
DISPLAY INVISIBLE (3925 1700);
FORCEPROP 2 LAST CDS_SEC 1
J 0
(3925 1700);
DISPLAY 1.021277 (3925 1700);
DISPLAY INVISIBLE (3925 1700);
FORCEPROP 1 LAST PATH I132
J 0
(3925 1650);
DISPLAY 0.978723 (3925 1650);
PAINT WHITE (3925 1650);
DISPLAY INVISIBLE (3925 1650);
FORCEADD Q_CAP..1
(3400 2250);
FORCEPROP 1 LAST PART_NUMBER CH622KMEB01
J 0
(3450 2100);
DISPLAY 0.638298 (3450 2100);
DISPLAY INVISIBLE (3450 2100);
FORCEPROP 1 LAST PACK_TYPE C0402
J 0
(3450 2050);
DISPLAY 0.638298 (3450 2050);
FORCEPROP 1 LAST MATERIAL X6S
J 0
(3450 2150);
DISPLAY 0.638298 (3450 2150);
FORCEPROP 1 LAST VALUE 22UF
J 0
(3450 2300);
DISPLAY 0.638298 (3450 2300);
FORCEPROP 1 LAST VOLTAGE 4V
J 0
(3450 2250);
DISPLAY 0.638298 (3450 2250);
FORCEPROP 1 LAST TOLERANCE 20%
J 0
(3450 2200);
DISPLAY 0.638298 (3450 2200);
FORCEPROP 1 LAST $LOCATION C1035
J 0
(3450 2350);
DISPLAY 0.638298 (3450 2350);
FORCEPROP 1 LASTPIN (3400 2350) $PN 1
J 0
(3410 2330);
DISPLAY 0.787234 (3410 2330);
FORCEPROP 1 LASTPIN (3400 2150) $PN 2
J 0
(3410 2130);
DISPLAY 0.787234 (3410 2130);
FORCEPROP 2 LAST CDS_LIB pure_quanta
J 0
(3400 2250);
PAINT MONO (3400 2250);
DISPLAY INVISIBLE (3400 2250);
FORCEPROP 2 LAST CDS_LOCATION C1035
J 0
(3450 2450);
DISPLAY 1.021277 (3450 2450);
DISPLAY INVISIBLE (3450 2450);
FORCEPROP 2 LAST $SEC 1
J 0
(3450 2450);
DISPLAY 0.680851 (3450 2450);
PAINT MONO (3450 2450);
DISPLAY INVISIBLE (3450 2450);
FORCEPROP 2 LAST CDS_SEC 1
J 0
(3450 2450);
DISPLAY 1.021277 (3450 2450);
DISPLAY INVISIBLE (3450 2450);
FORCEPROP 1 LAST PATH I133
J 0
(3450 2400);
DISPLAY 0.978723 (3450 2400);
PAINT WHITE (3450 2400);
DISPLAY INVISIBLE (3450 2400);
FORCEADD Q_CAP..1
(3400 3025);
FORCEPROP 1 LAST PART_NUMBER CH622KMEB01
J 0
(3450 2875);
DISPLAY 0.638298 (3450 2875);
DISPLAY INVISIBLE (3450 2875);
FORCEPROP 1 LAST MATERIAL X6S
J 0
(3450 2925);
DISPLAY 0.638298 (3450 2925);
FORCEPROP 1 LAST PACK_TYPE C0402
J 0
(3450 2825);
DISPLAY 0.638298 (3450 2825);
FORCEPROP 1 LAST VALUE 22UF
J 0
(3450 3075);
DISPLAY 0.638298 (3450 3075);
FORCEPROP 1 LAST VOLTAGE 4V
J 0
(3450 3025);
DISPLAY 0.638298 (3450 3025);
FORCEPROP 1 LAST TOLERANCE 20%
J 0
(3450 2975);
DISPLAY 0.638298 (3450 2975);
FORCEPROP 1 LAST $LOCATION C1034
J 0
(3450 3125);
DISPLAY 0.638298 (3450 3125);
FORCEPROP 1 LASTPIN (3400 3125) $PN 1
J 0
(3410 3105);
DISPLAY 0.787234 (3410 3105);
FORCEPROP 1 LASTPIN (3400 2925) $PN 2
J 0
(3410 2905);
DISPLAY 0.787234 (3410 2905);
FORCEPROP 2 LAST CDS_LIB pure_quanta
J 0
(3400 3025);
PAINT MONO (3400 3025);
DISPLAY INVISIBLE (3400 3025);
FORCEPROP 2 LAST CDS_LOCATION C1034
J 0
(3450 3225);
DISPLAY 1.021277 (3450 3225);
DISPLAY INVISIBLE (3450 3225);
FORCEPROP 2 LAST $SEC 1
J 0
(3450 3225);
DISPLAY 0.680851 (3450 3225);
PAINT MONO (3450 3225);
DISPLAY INVISIBLE (3450 3225);
FORCEPROP 2 LAST CDS_SEC 1
J 0
(3450 3225);
DISPLAY 1.021277 (3450 3225);
DISPLAY INVISIBLE (3450 3225);
FORCEPROP 1 LAST PATH I134
J 0
(3450 3175);
DISPLAY 0.978723 (3450 3175);
PAINT WHITE (3450 3175);
DISPLAY INVISIBLE (3450 3175);
FORCEADD Q_CAP..1
(3850 2250);
FORCEPROP 1 LAST PART_NUMBER CH622KMEB01
J 0
(3900 2100);
DISPLAY 0.638298 (3900 2100);
DISPLAY INVISIBLE (3900 2100);
FORCEPROP 1 LAST MATERIAL X6S
J 0
(3900 2150);
DISPLAY 0.638298 (3900 2150);
FORCEPROP 1 LAST PACK_TYPE C0402
J 0
(3900 2050);
DISPLAY 0.638298 (3900 2050);
FORCEPROP 1 LAST VALUE 22UF
J 0
(3900 2300);
DISPLAY 0.638298 (3900 2300);
FORCEPROP 1 LAST TOLERANCE 20%
J 0
(3900 2200);
DISPLAY 0.638298 (3900 2200);
FORCEPROP 1 LAST VOLTAGE 4V
J 0
(3900 2250);
DISPLAY 0.638298 (3900 2250);
FORCEPROP 1 LAST $LOCATION C1039
J 0
(3900 2350);
DISPLAY 0.638298 (3900 2350);
FORCEPROP 1 LASTPIN (3850 2350) $PN 1
J 0
(3860 2330);
DISPLAY 0.787234 (3860 2330);
FORCEPROP 1 LASTPIN (3850 2150) $PN 2
J 0
(3860 2130);
DISPLAY 0.787234 (3860 2130);
FORCEPROP 2 LAST CDS_LIB pure_quanta
J 0
(3850 2250);
PAINT MONO (3850 2250);
DISPLAY INVISIBLE (3850 2250);
FORCEPROP 2 LAST CDS_LOCATION C1039
J 0
(3900 2450);
DISPLAY 1.021277 (3900 2450);
DISPLAY INVISIBLE (3900 2450);
FORCEPROP 2 LAST $SEC 1
J 0
(3900 2450);
DISPLAY 0.680851 (3900 2450);
PAINT MONO (3900 2450);
DISPLAY INVISIBLE (3900 2450);
FORCEPROP 2 LAST CDS_SEC 1
J 0
(3900 2450);
DISPLAY 1.021277 (3900 2450);
DISPLAY INVISIBLE (3900 2450);
FORCEPROP 1 LAST PATH I135
J 0
(3900 2400);
DISPLAY 0.978723 (3900 2400);
PAINT WHITE (3900 2400);
DISPLAY INVISIBLE (3900 2400);
FORCEADD UNIVERSAL_GND..1
(3850 2675);
FORCEPROP 3 LASTPIN (3850 2725) SIG_NAME GND\g
J 0
(3860 2735);
DISPLAY 0.659574 (3860 2735);
PAINT MONO (3860 2735);
DISPLAY INVISIBLE (3860 2735);
FORCEPROP 2 LAST CDS_LIB logical_power
J 0
(3850 2675);
PAINT MONO (3850 2675);
DISPLAY INVISIBLE (3850 2675);
FORCEPROP 1 LAST HDL_POWER GND
J 1
(3875 2600);
DISPLAY 0.872340 (3875 2600);
PAINT GREEN (3875 2600);
DISPLAY INVISIBLE (3875 2600);
FORCEPROP 1 LAST PATH I136
J 0
(3925 2675);
DISPLAY 0.872340 (3925 2675);
PAINT AQUA (3925 2675);
DISPLAY INVISIBLE (3925 2675);
FORCEADD Q_CAP..1
(3850 3025);
FORCEPROP 1 LAST PART_NUMBER CH622KMEB01
J 0
(3900 2875);
DISPLAY 0.638298 (3900 2875);
DISPLAY INVISIBLE (3900 2875);
FORCEPROP 1 LAST PACK_TYPE C0402
J 0
(3900 2825);
DISPLAY 0.638298 (3900 2825);
FORCEPROP 1 LAST MATERIAL X6S
J 0
(3900 2925);
DISPLAY 0.638298 (3900 2925);
FORCEPROP 1 LAST TOLERANCE 20%
J 0
(3900 2975);
DISPLAY 0.638298 (3900 2975);
FORCEPROP 1 LAST VALUE 22UF
J 0
(3900 3075);
DISPLAY 0.638298 (3900 3075);
FORCEPROP 1 LAST VOLTAGE 4V
J 0
(3900 3025);
DISPLAY 0.638298 (3900 3025);
FORCEPROP 1 LAST $LOCATION C1038
J 0
(3900 3125);
DISPLAY 0.638298 (3900 3125);
FORCEPROP 1 LASTPIN (3850 3125) $PN 1
J 0
(3860 3105);
DISPLAY 0.787234 (3860 3105);
FORCEPROP 1 LASTPIN (3850 2925) $PN 2
J 0
(3860 2905);
DISPLAY 0.787234 (3860 2905);
FORCEPROP 2 LAST CDS_LIB pure_quanta
J 0
(3850 3025);
PAINT MONO (3850 3025);
DISPLAY INVISIBLE (3850 3025);
FORCEPROP 2 LAST CDS_LOCATION C1038
J 0
(3900 3225);
DISPLAY 1.021277 (3900 3225);
DISPLAY INVISIBLE (3900 3225);
FORCEPROP 2 LAST $SEC 1
J 0
(3900 3225);
DISPLAY 0.680851 (3900 3225);
PAINT MONO (3900 3225);
DISPLAY INVISIBLE (3900 3225);
FORCEPROP 2 LAST CDS_SEC 1
J 0
(3900 3225);
DISPLAY 1.021277 (3900 3225);
DISPLAY INVISIBLE (3900 3225);
FORCEPROP 1 LAST PATH I137
J 0
(3900 3175);
DISPLAY 0.978723 (3900 3175);
PAINT WHITE (3900 3175);
DISPLAY INVISIBLE (3900 3175);
FORCEADD UNIVERSAL_GND..1
(4325 1150);
FORCEPROP 3 LASTPIN (4325 1200) SIG_NAME GND\g
J 0
(4335 1210);
DISPLAY 0.659574 (4335 1210);
PAINT MONO (4335 1210);
DISPLAY INVISIBLE (4335 1210);
FORCEPROP 2 LAST CDS_LIB logical_power
J 0
(4325 1150);
PAINT MONO (4325 1150);
DISPLAY INVISIBLE (4325 1150);
FORCEPROP 1 LAST HDL_POWER GND
J 1
(4350 1075);
DISPLAY 0.872340 (4350 1075);
PAINT GREEN (4350 1075);
DISPLAY INVISIBLE (4350 1075);
FORCEPROP 1 LAST PATH I138
J 0
(4400 1150);
DISPLAY 0.872340 (4400 1150);
PAINT AQUA (4400 1150);
DISPLAY INVISIBLE (4400 1150);
FORCEADD Q_CAP..1
(4325 1500);
FORCEPROP 1 LAST PART_NUMBER CH622KMEB01
J 0
(4375 1350);
DISPLAY 0.638298 (4375 1350);
DISPLAY INVISIBLE (4375 1350);
FORCEPROP 1 LAST PACK_TYPE C0402
J 0
(4375 1300);
DISPLAY 0.638298 (4375 1300);
FORCEPROP 1 LAST MATERIAL X6S
J 0
(4375 1400);
DISPLAY 0.638298 (4375 1400);
FORCEPROP 1 LAST VOLTAGE 4V
J 0
(4375 1500);
DISPLAY 0.638298 (4375 1500);
FORCEPROP 1 LAST VALUE 22UF
J 0
(4375 1550);
DISPLAY 0.638298 (4375 1550);
FORCEPROP 1 LAST TOLERANCE 20%
J 0
(4375 1450);
DISPLAY 0.638298 (4375 1450);
FORCEPROP 1 LAST $LOCATION C1044
J 0
(4375 1600);
DISPLAY 0.638298 (4375 1600);
FORCEPROP 1 LASTPIN (4325 1600) $PN 1
J 0
(4335 1580);
DISPLAY 0.787234 (4335 1580);
FORCEPROP 1 LASTPIN (4325 1400) $PN 2
J 0
(4335 1380);
DISPLAY 0.787234 (4335 1380);
FORCEPROP 2 LAST CDS_LIB pure_quanta
J 0
(4325 1500);
PAINT MONO (4325 1500);
DISPLAY INVISIBLE (4325 1500);
FORCEPROP 2 LAST CDS_LOCATION C1044
J 0
(4375 1700);
DISPLAY 1.021277 (4375 1700);
DISPLAY INVISIBLE (4375 1700);
FORCEPROP 2 LAST $SEC 1
J 0
(4375 1700);
DISPLAY 0.680851 (4375 1700);
PAINT MONO (4375 1700);
DISPLAY INVISIBLE (4375 1700);
FORCEPROP 2 LAST CDS_SEC 1
J 0
(4375 1700);
DISPLAY 1.021277 (4375 1700);
DISPLAY INVISIBLE (4375 1700);
FORCEPROP 1 LAST PATH I139
J 0
(4375 1650);
DISPLAY 0.978723 (4375 1650);
PAINT WHITE (4375 1650);
DISPLAY INVISIBLE (4375 1650);
FORCEADD UNIVERSAL_POWER..1
(-4250 225);
FORCEPROP 3 LASTPIN (-4250 175) SIG_NAME PVCCIN_CPU0\g
J 0
(-4240 185);
DISPLAY 0.659574 (-4240 185);
PAINT MONO (-4240 185);
DISPLAY INVISIBLE (-4240 185);
FORCEPROP 1 LAST HDL_POWER PVCCIN_CPU0
J 1
(-4050 275);
DISPLAY 0.872340 (-4050 275);
PAINT GREEN (-4050 275);
FORCEPROP 2 LAST CDS_LIB logical_power
J 0
(-4250 225);
DISPLAY INVISIBLE (-4250 225);
FORCEPROP 1 LAST PATH I14
J 0
(-4200 250);
DISPLAY 0.872340 (-4200 250);
PAINT AQUA (-4200 250);
DISPLAY INVISIBLE (-4200 250);
FORCEADD UNIVERSAL_GND..1
(4300 1900);
FORCEPROP 3 LASTPIN (4300 1950) SIG_NAME GND\g
J 0
(4310 1960);
DISPLAY 0.659574 (4310 1960);
PAINT MONO (4310 1960);
DISPLAY INVISIBLE (4310 1960);
FORCEPROP 2 LAST CDS_LIB logical_power
J 0
(4300 1900);
PAINT MONO (4300 1900);
DISPLAY INVISIBLE (4300 1900);
FORCEPROP 1 LAST HDL_POWER GND
J 1
(4325 1825);
DISPLAY 0.872340 (4325 1825);
PAINT GREEN (4325 1825);
DISPLAY INVISIBLE (4325 1825);
FORCEPROP 1 LAST PATH I140
J 0
(4375 1900);
DISPLAY 0.872340 (4375 1900);
PAINT AQUA (4375 1900);
DISPLAY INVISIBLE (4375 1900);
FORCEADD Q_CAP..1
(4300 2250);
FORCEPROP 1 LAST PART_NUMBER CH622KMEB01
J 0
(4350 2100);
DISPLAY 0.638298 (4350 2100);
DISPLAY INVISIBLE (4350 2100);
FORCEPROP 1 LAST VALUE 22UF
J 0
(4350 2300);
DISPLAY 0.638298 (4350 2300);
FORCEPROP 1 LAST MATERIAL X6S
J 0
(4350 2150);
DISPLAY 0.638298 (4350 2150);
FORCEPROP 1 LAST PACK_TYPE C0402
J 0
(4350 2050);
DISPLAY 0.638298 (4350 2050);
FORCEPROP 1 LAST TOLERANCE 20%
J 0
(4350 2200);
DISPLAY 0.638298 (4350 2200);
FORCEPROP 1 LAST VOLTAGE 4V
J 0
(4350 2250);
DISPLAY 0.638298 (4350 2250);
FORCEPROP 1 LAST $LOCATION C1043
J 0
(4350 2350);
DISPLAY 0.638298 (4350 2350);
FORCEPROP 1 LASTPIN (4300 2350) $PN 1
J 0
(4310 2330);
DISPLAY 0.787234 (4310 2330);
FORCEPROP 1 LASTPIN (4300 2150) $PN 2
J 0
(4310 2130);
DISPLAY 0.787234 (4310 2130);
FORCEPROP 2 LAST CDS_LIB pure_quanta
J 0
(4300 2250);
PAINT MONO (4300 2250);
DISPLAY INVISIBLE (4300 2250);
FORCEPROP 2 LAST CDS_LOCATION C1043
J 0
(4350 2450);
DISPLAY 1.021277 (4350 2450);
DISPLAY INVISIBLE (4350 2450);
FORCEPROP 2 LAST $SEC 1
J 0
(4350 2450);
DISPLAY 0.680851 (4350 2450);
PAINT MONO (4350 2450);
DISPLAY INVISIBLE (4350 2450);
FORCEPROP 2 LAST CDS_SEC 1
J 0
(4350 2450);
DISPLAY 1.021277 (4350 2450);
DISPLAY INVISIBLE (4350 2450);
FORCEPROP 1 LAST PATH I141
J 0
(4350 2400);
DISPLAY 0.978723 (4350 2400);
PAINT WHITE (4350 2400);
DISPLAY INVISIBLE (4350 2400);
FORCEADD Q_CAP..1
(-2000 -850);
FORCEPROP 1 LAST PART_NUMBER CH622KMEB01
J 0
(-1950 -1000);
DISPLAY 0.638298 (-1950 -1000);
DISPLAY INVISIBLE (-1950 -1000);
FORCEPROP 1 LAST MATERIAL X6S
J 0
(-1950 -950);
DISPLAY 0.638298 (-1950 -950);
FORCEPROP 1 LAST PACK_TYPE C0402
J 0
(-1950 -1050);
DISPLAY 0.638298 (-1950 -1050);
FORCEPROP 1 LAST VOLTAGE 4V
J 0
(-1950 -850);
DISPLAY 0.638298 (-1950 -850);
FORCEPROP 1 LAST VALUE 22UF
J 0
(-1950 -800);
DISPLAY 0.638298 (-1950 -800);
FORCEPROP 1 LAST TOLERANCE 20%
J 0
(-1950 -900);
DISPLAY 0.638298 (-1950 -900);
FORCEPROP 1 LAST $LOCATION C408
J 0
(-1950 -750);
DISPLAY 0.978723 (-1950 -750);
FORCEPROP 1 LASTPIN (-2000 -750) $PN 1
J 0
(-1990 -770);
DISPLAY 0.787234 (-1990 -770);
FORCEPROP 1 LASTPIN (-2000 -950) $PN 2
J 0
(-1990 -970);
DISPLAY 0.787234 (-1990 -970);
FORCEPROP 2 LAST CDS_LIB pure_quanta
J 0
(-2000 -850);
PAINT MONO (-2000 -850);
DISPLAY INVISIBLE (-2000 -850);
FORCEPROP 2 LAST CDS_LOCATION C408
J 0
(-1950 -650);
DISPLAY 1.021277 (-1950 -650);
DISPLAY INVISIBLE (-1950 -650);
FORCEPROP 2 LAST $SEC 1
J 0
(-1950 -650);
DISPLAY 0.680851 (-1950 -650);
PAINT MONO (-1950 -650);
DISPLAY INVISIBLE (-1950 -650);
FORCEPROP 2 LAST CDS_SEC 1
J 0
(-1950 -650);
DISPLAY 1.021277 (-1950 -650);
DISPLAY INVISIBLE (-1950 -650);
FORCEPROP 1 LAST PATH I142
J 0
(-1950 -700);
DISPLAY 0.978723 (-1950 -700);
PAINT WHITE (-1950 -700);
DISPLAY INVISIBLE (-1950 -700);
FORCEADD Q_CAP..1
(-4250 725);
FORCEPROP 1 LAST PART_NUMBER CH6101MEB03
J 0
(-4200 575);
DISPLAY 0.638298 (-4200 575);
DISPLAY INVISIBLE (-4200 575);
FORCEPROP 1 LAST VALUE 10UF
J 0
(-4200 775);
DISPLAY 0.638298 (-4200 775);
FORCEPROP 1 LAST PACK_TYPE C0402
J 0
(-4200 525);
DISPLAY 0.638298 (-4200 525);
FORCEPROP 1 LAST MATERIAL X6S
J 0
(-4200 625);
DISPLAY 0.638298 (-4200 625);
FORCEPROP 1 LAST VOLTAGE 6.3V
J 0
(-4200 725);
DISPLAY 0.638298 (-4200 725);
FORCEPROP 1 LAST TOLERANCE 20%
J 0
(-4200 675);
DISPLAY 0.638298 (-4200 675);
FORCEPROP 1 LAST $LOCATION C969
J 0
(-4200 825);
DISPLAY 0.638298 (-4200 825);
FORCEPROP 1 LASTPIN (-4250 825) $PN 1
J 0
(-4240 805);
DISPLAY 0.787234 (-4240 805);
FORCEPROP 1 LASTPIN (-4250 625) $PN 2
J 0
(-4240 605);
DISPLAY 0.787234 (-4240 605);
FORCEPROP 2 LAST CDS_LIB pure_quanta
J 0
(-4250 725);
PAINT MONO (-4250 725);
DISPLAY INVISIBLE (-4250 725);
FORCEPROP 2 LAST CDS_LOCATION C969
J 0
(-4200 925);
DISPLAY 1.021277 (-4200 925);
DISPLAY INVISIBLE (-4200 925);
FORCEPROP 2 LAST $SEC 1
J 0
(-4200 925);
DISPLAY 0.680851 (-4200 925);
PAINT MONO (-4200 925);
DISPLAY INVISIBLE (-4200 925);
FORCEPROP 2 LAST CDS_SEC 1
J 0
(-4200 925);
DISPLAY 1.021277 (-4200 925);
DISPLAY INVISIBLE (-4200 925);
FORCEPROP 1 LAST PATH I15
J 0
(-4200 875);
DISPLAY 0.978723 (-4200 875);
PAINT WHITE (-4200 875);
DISPLAY INVISIBLE (-4200 875);
FORCEADD UNIVERSAL_POWER..1
(-4250 1000);
FORCEPROP 3 LASTPIN (-4250 950) SIG_NAME PVCCIN_CPU0\g
J 0
(-4240 960);
DISPLAY 0.659574 (-4240 960);
PAINT MONO (-4240 960);
DISPLAY INVISIBLE (-4240 960);
FORCEPROP 1 LAST HDL_POWER PVCCIN_CPU0
J 1
(-4050 1050);
DISPLAY 0.872340 (-4050 1050);
PAINT GREEN (-4050 1050);
FORCEPROP 2 LAST CDS_LIB logical_power
J 0
(-4250 1000);
DISPLAY INVISIBLE (-4250 1000);
FORCEPROP 1 LAST PATH I16
J 0
(-4200 1025);
DISPLAY 0.872340 (-4200 1025);
PAINT AQUA (-4200 1025);
DISPLAY INVISIBLE (-4200 1025);
FORCEADD Q_CAP..1
(-3800 -850);
FORCEPROP 1 LAST PART_NUMBER CH622KMEB01
J 0
(-3750 -1000);
DISPLAY 0.638298 (-3750 -1000);
DISPLAY INVISIBLE (-3750 -1000);
FORCEPROP 1 LAST PACK_TYPE C0402
J 0
(-3750 -1050);
DISPLAY 0.638298 (-3750 -1050);
FORCEPROP 1 LAST VOLTAGE 4V
J 0
(-3750 -850);
DISPLAY 0.638298 (-3750 -850);
FORCEPROP 1 LAST VALUE 22UF
J 0
(-3750 -800);
DISPLAY 0.638298 (-3750 -800);
FORCEPROP 1 LAST MATERIAL X6S
J 0
(-3750 -950);
DISPLAY 0.638298 (-3750 -950);
FORCEPROP 1 LAST TOLERANCE 20%
J 0
(-3750 -900);
DISPLAY 0.638298 (-3750 -900);
FORCEPROP 1 LAST $LOCATION C401
J 0
(-3750 -750);
DISPLAY 0.978723 (-3750 -750);
FORCEPROP 1 LASTPIN (-3800 -750) $PN 1
J 0
(-3790 -770);
DISPLAY 0.787234 (-3790 -770);
FORCEPROP 1 LASTPIN (-3800 -950) $PN 2
J 0
(-3790 -970);
DISPLAY 0.787234 (-3790 -970);
FORCEPROP 2 LAST CDS_LIB pure_quanta
J 0
(-3800 -850);
PAINT MONO (-3800 -850);
DISPLAY INVISIBLE (-3800 -850);
FORCEPROP 2 LAST CDS_LOCATION C401
J 0
(-3750 -650);
DISPLAY 1.021277 (-3750 -650);
DISPLAY INVISIBLE (-3750 -650);
FORCEPROP 2 LAST $SEC 1
J 0
(-3750 -650);
DISPLAY 0.680851 (-3750 -650);
PAINT MONO (-3750 -650);
DISPLAY INVISIBLE (-3750 -650);
FORCEPROP 2 LAST CDS_SEC 1
J 0
(-3750 -650);
DISPLAY 1.021277 (-3750 -650);
DISPLAY INVISIBLE (-3750 -650);
FORCEPROP 1 LAST PATH I17
J 0
(-3750 -700);
DISPLAY 0.978723 (-3750 -700);
PAINT WHITE (-3750 -700);
DISPLAY INVISIBLE (-3750 -700);
FORCEADD Q_CAP..1
(-3800 -50);
FORCEPROP 1 LAST PART_NUMBER CH647KMEA04
J 0
(-3750 -200);
DISPLAY 0.638298 (-3750 -200);
DISPLAY INVISIBLE (-3750 -200);
FORCEPROP 1 LAST MATERIAL X6S
J 0
(-3750 -150);
DISPLAY 0.638298 (-3750 -150);
FORCEPROP 1 LAST PACK_TYPE C0805
J 0
(-3750 -250);
DISPLAY 0.638298 (-3750 -250);
FORCEPROP 1 LAST VOLTAGE 4V
J 0
(-3750 -50);
DISPLAY 0.638298 (-3750 -50);
FORCEPROP 1 LAST TOLERANCE 20%
J 0
(-3750 -100);
DISPLAY 0.638298 (-3750 -100);
FORCEPROP 1 LAST VALUE 47UF
J 0
(-3750 0);
DISPLAY 0.638298 (-3750 0);
FORCEPROP 1 LAST $LOCATION C212
J 0
(-3750 50);
DISPLAY 0.638298 (-3750 50);
FORCEPROP 1 LASTPIN (-3800 50) $PN 1
J 0
(-3790 30);
DISPLAY 0.787234 (-3790 30);
FORCEPROP 1 LASTPIN (-3800 -150) $PN 2
J 0
(-3790 -170);
DISPLAY 0.787234 (-3790 -170);
FORCEPROP 2 LAST CDS_LIB pure_quanta
J 0
(-3800 -50);
PAINT MONO (-3800 -50);
DISPLAY INVISIBLE (-3800 -50);
FORCEPROP 1 LAST $LOCATION C212
J 0
(-3750 150);
DISPLAY 1.021277 (-3750 150);
DISPLAY INVISIBLE (-3750 150);
FORCEPROP 2 LAST CDS_LOCATION C212
J 0
(-3750 150);
DISPLAY 1.021277 (-3750 150);
DISPLAY INVISIBLE (-3750 150);
FORCEPROP 2 LAST $SEC 1
J 0
(-3750 150);
DISPLAY 0.680851 (-3750 150);
PAINT MONO (-3750 150);
DISPLAY INVISIBLE (-3750 150);
FORCEPROP 2 LAST CDS_SEC 1
J 0
(-3750 150);
DISPLAY 1.021277 (-3750 150);
DISPLAY INVISIBLE (-3750 150);
FORCEPROP 1 LAST PATH I18
J 0
(-3750 100);
DISPLAY 0.978723 (-3750 100);
PAINT WHITE (-3750 100);
DISPLAY INVISIBLE (-3750 100);
FORCEADD Q_CAP..1
(-3350 -850);
FORCEPROP 1 LAST PART_NUMBER CH622KMEB01
J 0
(-3300 -1000);
DISPLAY 0.638298 (-3300 -1000);
DISPLAY INVISIBLE (-3300 -1000);
FORCEPROP 1 LAST VALUE 22UF
J 0
(-3300 -800);
DISPLAY 0.638298 (-3300 -800);
FORCEPROP 1 LAST VOLTAGE 4V
J 0
(-3300 -850);
DISPLAY 0.638298 (-3300 -850);
FORCEPROP 1 LAST MATERIAL X6S
J 0
(-3300 -950);
DISPLAY 0.638298 (-3300 -950);
FORCEPROP 1 LAST TOLERANCE 20%
J 0
(-3300 -900);
DISPLAY 0.638298 (-3300 -900);
FORCEPROP 1 LAST PACK_TYPE C0402
J 0
(-3300 -1050);
DISPLAY 0.638298 (-3300 -1050);
FORCEPROP 1 LAST $LOCATION C403
J 0
(-3300 -750);
DISPLAY 0.978723 (-3300 -750);
FORCEPROP 1 LASTPIN (-3350 -750) $PN 1
J 0
(-3340 -770);
DISPLAY 0.787234 (-3340 -770);
FORCEPROP 1 LASTPIN (-3350 -950) $PN 2
J 0
(-3340 -970);
DISPLAY 0.787234 (-3340 -970);
FORCEPROP 2 LAST CDS_LIB pure_quanta
J 0
(-3350 -850);
PAINT MONO (-3350 -850);
DISPLAY INVISIBLE (-3350 -850);
FORCEPROP 2 LAST CDS_LOCATION C403
J 0
(-3300 -650);
DISPLAY 1.021277 (-3300 -650);
DISPLAY INVISIBLE (-3300 -650);
FORCEPROP 2 LAST $SEC 1
J 0
(-3300 -650);
DISPLAY 0.680851 (-3300 -650);
PAINT MONO (-3300 -650);
DISPLAY INVISIBLE (-3300 -650);
FORCEPROP 2 LAST CDS_SEC 1
J 0
(-3300 -650);
DISPLAY 1.021277 (-3300 -650);
DISPLAY INVISIBLE (-3300 -650);
FORCEPROP 1 LAST PATH I19
J 0
(-3300 -700);
DISPLAY 0.978723 (-3300 -700);
PAINT WHITE (-3300 -700);
DISPLAY INVISIBLE (-3300 -700);
FORCEADD UNIVERSAL_POWER..1
(-4250 -1375);
FORCEPROP 3 LASTPIN (-4250 -1425) SIG_NAME PVCCFA_EHV_FIVRA_CPU0\g
J 0
(-4240 -1415);
DISPLAY 0.659574 (-4240 -1415);
PAINT MONO (-4240 -1415);
DISPLAY INVISIBLE (-4240 -1415);
FORCEPROP 1 LAST HDL_POWER PVCCFA_EHV_FIVRA_CPU0
J 1
(-3850 -1325);
DISPLAY 0.872340 (-3850 -1325);
PAINT GREEN (-3850 -1325);
FORCEPROP 2 LAST CDS_LIB logical_power
J 0
(-4250 -1375);
DISPLAY INVISIBLE (-4250 -1375);
FORCEPROP 1 LAST PATH I2
J 0
(-4200 -1350);
DISPLAY 0.872340 (-4200 -1350);
PAINT AQUA (-4200 -1350);
DISPLAY INVISIBLE (-4200 -1350);
FORCEADD Q_CAP..1
(-3350 -50);
FORCEPROP 1 LAST PART_NUMBER CH647KMEA04
J 0
(-3300 -200);
DISPLAY 0.638298 (-3300 -200);
DISPLAY INVISIBLE (-3300 -200);
FORCEPROP 1 LAST MATERIAL X6S
J 0
(-3300 -150);
DISPLAY 0.638298 (-3300 -150);
FORCEPROP 1 LAST PACK_TYPE C0805
J 0
(-3300 -250);
DISPLAY 0.638298 (-3300 -250);
FORCEPROP 1 LAST VOLTAGE 4V
J 0
(-3300 -50);
DISPLAY 0.638298 (-3300 -50);
FORCEPROP 1 LAST TOLERANCE 20%
J 0
(-3300 -100);
DISPLAY 0.638298 (-3300 -100);
FORCEPROP 1 LAST VALUE 47UF
J 0
(-3300 0);
DISPLAY 0.638298 (-3300 0);
FORCEPROP 1 LAST $LOCATION C213
J 0
(-3300 50);
DISPLAY 0.638298 (-3300 50);
FORCEPROP 1 LASTPIN (-3350 50) $PN 1
J 0
(-3340 30);
DISPLAY 0.787234 (-3340 30);
FORCEPROP 1 LASTPIN (-3350 -150) $PN 2
J 0
(-3340 -170);
DISPLAY 0.787234 (-3340 -170);
FORCEPROP 2 LAST CDS_LIB pure_quanta
J 0
(-3350 -50);
PAINT MONO (-3350 -50);
DISPLAY INVISIBLE (-3350 -50);
FORCEPROP 1 LAST $LOCATION C213
J 0
(-3300 150);
DISPLAY 1.021277 (-3300 150);
DISPLAY INVISIBLE (-3300 150);
FORCEPROP 2 LAST CDS_LOCATION C213
J 0
(-3300 150);
DISPLAY 1.021277 (-3300 150);
DISPLAY INVISIBLE (-3300 150);
FORCEPROP 2 LAST $SEC 1
J 0
(-3300 150);
DISPLAY 0.680851 (-3300 150);
PAINT MONO (-3300 150);
DISPLAY INVISIBLE (-3300 150);
FORCEPROP 2 LAST CDS_SEC 1
J 0
(-3300 150);
DISPLAY 1.021277 (-3300 150);
DISPLAY INVISIBLE (-3300 150);
FORCEPROP 1 LAST PATH I20
J 0
(-3300 100);
DISPLAY 0.978723 (-3300 100);
PAINT WHITE (-3300 100);
DISPLAY INVISIBLE (-3300 100);
FORCEADD Q_CAP..1
(-3800 725);
FORCEPROP 1 LAST PART_NUMBER CH6101MEB03
J 0
(-3750 575);
DISPLAY 0.638298 (-3750 575);
DISPLAY INVISIBLE (-3750 575);
FORCEPROP 1 LAST VALUE 10UF
J 0
(-3750 775);
DISPLAY 0.638298 (-3750 775);
FORCEPROP 1 LAST PACK_TYPE C0402
J 0
(-3750 525);
DISPLAY 0.638298 (-3750 525);
FORCEPROP 1 LAST MATERIAL X6S
J 0
(-3750 625);
DISPLAY 0.638298 (-3750 625);
FORCEPROP 1 LAST VOLTAGE 6.3V
J 0
(-3750 725);
DISPLAY 0.638298 (-3750 725);
FORCEPROP 1 LAST TOLERANCE 20%
J 0
(-3750 675);
DISPLAY 0.638298 (-3750 675);
FORCEPROP 1 LAST $LOCATION C973
J 0
(-3750 825);
DISPLAY 0.638298 (-3750 825);
FORCEPROP 1 LASTPIN (-3800 825) $PN 1
J 0
(-3790 805);
DISPLAY 0.787234 (-3790 805);
FORCEPROP 1 LASTPIN (-3800 625) $PN 2
J 0
(-3790 605);
DISPLAY 0.787234 (-3790 605);
FORCEPROP 2 LAST CDS_LIB pure_quanta
J 0
(-3800 725);
PAINT MONO (-3800 725);
DISPLAY INVISIBLE (-3800 725);
FORCEPROP 2 LAST CDS_LOCATION C973
J 0
(-3750 925);
DISPLAY 1.021277 (-3750 925);
DISPLAY INVISIBLE (-3750 925);
FORCEPROP 2 LAST $SEC 1
J 0
(-3750 925);
DISPLAY 0.680851 (-3750 925);
PAINT MONO (-3750 925);
DISPLAY INVISIBLE (-3750 925);
FORCEPROP 2 LAST CDS_SEC 1
J 0
(-3750 925);
DISPLAY 1.021277 (-3750 925);
DISPLAY INVISIBLE (-3750 925);
FORCEPROP 1 LAST PATH I21
J 0
(-3750 875);
DISPLAY 0.978723 (-3750 875);
PAINT WHITE (-3750 875);
DISPLAY INVISIBLE (-3750 875);
FORCEADD Q_CAP..1
(-3350 725);
FORCEPROP 1 LAST PART_NUMBER CH6101MEB03
J 0
(-3300 575);
DISPLAY 0.638298 (-3300 575);
DISPLAY INVISIBLE (-3300 575);
FORCEPROP 1 LAST VALUE 10UF
J 0
(-3300 775);
DISPLAY 0.638298 (-3300 775);
FORCEPROP 1 LAST PACK_TYPE C0402
J 0
(-3300 525);
DISPLAY 0.638298 (-3300 525);
FORCEPROP 1 LAST MATERIAL X6S
J 0
(-3300 625);
DISPLAY 0.638298 (-3300 625);
FORCEPROP 1 LAST VOLTAGE 6.3V
J 0
(-3300 725);
DISPLAY 0.638298 (-3300 725);
FORCEPROP 1 LAST TOLERANCE 20%
J 0
(-3300 675);
DISPLAY 0.638298 (-3300 675);
FORCEPROP 1 LAST $LOCATION C977
J 0
(-3300 825);
DISPLAY 0.638298 (-3300 825);
FORCEPROP 1 LASTPIN (-3350 825) $PN 1
J 0
(-3340 805);
DISPLAY 0.787234 (-3340 805);
FORCEPROP 1 LASTPIN (-3350 625) $PN 2
J 0
(-3340 605);
DISPLAY 0.787234 (-3340 605);
FORCEPROP 2 LAST CDS_LIB pure_quanta
J 0
(-3350 725);
PAINT MONO (-3350 725);
DISPLAY INVISIBLE (-3350 725);
FORCEPROP 2 LAST CDS_LOCATION C977
J 0
(-3300 925);
DISPLAY 1.021277 (-3300 925);
DISPLAY INVISIBLE (-3300 925);
FORCEPROP 2 LAST $SEC 1
J 0
(-3300 925);
DISPLAY 0.680851 (-3300 925);
PAINT MONO (-3300 925);
DISPLAY INVISIBLE (-3300 925);
FORCEPROP 2 LAST CDS_SEC 1
J 0
(-3300 925);
DISPLAY 1.021277 (-3300 925);
DISPLAY INVISIBLE (-3300 925);
FORCEPROP 1 LAST PATH I22
J 0
(-3300 875);
DISPLAY 0.978723 (-3300 875);
PAINT WHITE (-3300 875);
DISPLAY INVISIBLE (-3300 875);
FORCEADD Q_CAP..1
(-4250 1500);
FORCEPROP 1 LAST PART_NUMBER CH6101MEB03
J 0
(-4200 1350);
DISPLAY 0.638298 (-4200 1350);
DISPLAY INVISIBLE (-4200 1350);
FORCEPROP 1 LAST MATERIAL X6S
J 0
(-4200 1400);
DISPLAY 0.638298 (-4200 1400);
FORCEPROP 1 LAST TOLERANCE 20%
J 0
(-4200 1450);
DISPLAY 0.638298 (-4200 1450);
FORCEPROP 1 LAST VALUE 10UF
J 0
(-4200 1550);
DISPLAY 0.638298 (-4200 1550);
FORCEPROP 1 LAST VOLTAGE 6.3V
J 0
(-4200 1500);
DISPLAY 0.638298 (-4200 1500);
FORCEPROP 1 LAST PACK_TYPE C0402
J 0
(-4200 1300);
DISPLAY 0.638298 (-4200 1300);
FORCEPROP 1 LAST $LOCATION C968
J 0
(-4200 1600);
DISPLAY 0.638298 (-4200 1600);
FORCEPROP 1 LASTPIN (-4250 1600) $PN 1
J 0
(-4240 1580);
DISPLAY 0.787234 (-4240 1580);
FORCEPROP 1 LASTPIN (-4250 1400) $PN 2
J 0
(-4240 1380);
DISPLAY 0.787234 (-4240 1380);
FORCEPROP 2 LAST CDS_LIB pure_quanta
J 0
(-4250 1500);
PAINT MONO (-4250 1500);
DISPLAY INVISIBLE (-4250 1500);
FORCEPROP 2 LAST CDS_LOCATION C968
J 0
(-4200 1700);
DISPLAY 1.021277 (-4200 1700);
DISPLAY INVISIBLE (-4200 1700);
FORCEPROP 2 LAST $SEC 1
J 0
(-4200 1700);
DISPLAY 0.680851 (-4200 1700);
PAINT MONO (-4200 1700);
DISPLAY INVISIBLE (-4200 1700);
FORCEPROP 2 LAST CDS_SEC 1
J 0
(-4200 1700);
DISPLAY 1.021277 (-4200 1700);
DISPLAY INVISIBLE (-4200 1700);
FORCEPROP 1 LAST PATH I23
J 0
(-4200 1650);
DISPLAY 0.978723 (-4200 1650);
PAINT WHITE (-4200 1650);
DISPLAY INVISIBLE (-4200 1650);
FORCEADD UNIVERSAL_POWER..1
(-4250 1775);
FORCEPROP 3 LASTPIN (-4250 1725) SIG_NAME PVCCIN_CPU0\g
J 0
(-4240 1735);
DISPLAY 0.659574 (-4240 1735);
PAINT MONO (-4240 1735);
DISPLAY INVISIBLE (-4240 1735);
FORCEPROP 1 LAST HDL_POWER PVCCIN_CPU0
J 1
(-4050 1825);
DISPLAY 0.872340 (-4050 1825);
PAINT GREEN (-4050 1825);
FORCEPROP 2 LAST CDS_LIB logical_power
J 0
(-4250 1775);
DISPLAY INVISIBLE (-4250 1775);
FORCEPROP 1 LAST PATH I24
J 0
(-4200 1800);
DISPLAY 0.872340 (-4200 1800);
PAINT AQUA (-4200 1800);
DISPLAY INVISIBLE (-4200 1800);
FORCEADD Q_CAP..1
(-4275 2250);
FORCEPROP 1 LAST PART_NUMBER CH6101MEB03
J 0
(-4225 2100);
DISPLAY 0.638298 (-4225 2100);
DISPLAY INVISIBLE (-4225 2100);
FORCEPROP 1 LAST PACK_TYPE C0402
J 0
(-4225 2050);
DISPLAY 0.638298 (-4225 2050);
FORCEPROP 1 LAST MATERIAL X6S
J 0
(-4225 2150);
DISPLAY 0.638298 (-4225 2150);
FORCEPROP 1 LAST TOLERANCE 20%
J 0
(-4225 2200);
DISPLAY 0.638298 (-4225 2200);
FORCEPROP 1 LAST VALUE 10UF
J 0
(-4225 2300);
DISPLAY 0.638298 (-4225 2300);
FORCEPROP 1 LAST VOLTAGE 6.3V
J 0
(-4225 2250);
DISPLAY 0.638298 (-4225 2250);
FORCEPROP 1 LAST $LOCATION C967
J 0
(-4225 2350);
DISPLAY 0.638298 (-4225 2350);
FORCEPROP 1 LASTPIN (-4275 2350) $PN 1
J 0
(-4265 2330);
DISPLAY 0.787234 (-4265 2330);
FORCEPROP 1 LASTPIN (-4275 2150) $PN 2
J 0
(-4265 2130);
DISPLAY 0.787234 (-4265 2130);
FORCEPROP 2 LAST CDS_LIB pure_quanta
J 0
(-4275 2250);
PAINT MONO (-4275 2250);
DISPLAY INVISIBLE (-4275 2250);
FORCEPROP 2 LAST CDS_LOCATION C967
J 0
(-4225 2450);
DISPLAY 1.021277 (-4225 2450);
DISPLAY INVISIBLE (-4225 2450);
FORCEPROP 2 LAST $SEC 1
J 0
(-4225 2450);
DISPLAY 0.680851 (-4225 2450);
PAINT MONO (-4225 2450);
DISPLAY INVISIBLE (-4225 2450);
FORCEPROP 2 LAST CDS_SEC 1
J 0
(-4225 2450);
DISPLAY 1.021277 (-4225 2450);
DISPLAY INVISIBLE (-4225 2450);
FORCEPROP 1 LAST PATH I25
J 0
(-4225 2400);
DISPLAY 0.978723 (-4225 2400);
PAINT WHITE (-4225 2400);
DISPLAY INVISIBLE (-4225 2400);
FORCEADD UNIVERSAL_POWER..1
(-4275 2525);
FORCEPROP 3 LASTPIN (-4275 2475) SIG_NAME PVCCIN_CPU0\g
J 0
(-4265 2485);
DISPLAY 0.659574 (-4265 2485);
PAINT MONO (-4265 2485);
DISPLAY INVISIBLE (-4265 2485);
FORCEPROP 1 LAST HDL_POWER PVCCIN_CPU0
J 1
(-4075 2575);
DISPLAY 0.872340 (-4075 2575);
PAINT GREEN (-4075 2575);
FORCEPROP 2 LAST CDS_LIB logical_power
J 0
(-4275 2525);
DISPLAY INVISIBLE (-4275 2525);
FORCEPROP 1 LAST PATH I26
J 0
(-4225 2550);
DISPLAY 0.872340 (-4225 2550);
PAINT AQUA (-4225 2550);
DISPLAY INVISIBLE (-4225 2550);
FORCEADD Q_CAP..1
(-4275 3025);
FORCEPROP 1 LAST PART_NUMBER CH6101MEB03
J 0
(-4225 2875);
DISPLAY 0.638298 (-4225 2875);
DISPLAY INVISIBLE (-4225 2875);
FORCEPROP 1 LAST PACK_TYPE C0402
J 0
(-4225 2825);
DISPLAY 0.638298 (-4225 2825);
FORCEPROP 1 LAST MATERIAL X6S
J 0
(-4225 2925);
DISPLAY 0.638298 (-4225 2925);
FORCEPROP 1 LAST TOLERANCE 20%
J 0
(-4225 2975);
DISPLAY 0.638298 (-4225 2975);
FORCEPROP 1 LAST VALUE 10UF
J 0
(-4225 3075);
DISPLAY 0.638298 (-4225 3075);
FORCEPROP 1 LAST VOLTAGE 6.3V
J 0
(-4225 3025);
DISPLAY 0.638298 (-4225 3025);
FORCEPROP 1 LAST $LOCATION C966
J 0
(-4225 3125);
DISPLAY 0.638298 (-4225 3125);
FORCEPROP 1 LASTPIN (-4275 3125) $PN 1
J 0
(-4265 3105);
DISPLAY 0.787234 (-4265 3105);
FORCEPROP 1 LASTPIN (-4275 2925) $PN 2
J 0
(-4265 2905);
DISPLAY 0.787234 (-4265 2905);
FORCEPROP 2 LAST CDS_LIB pure_quanta
J 0
(-4275 3025);
PAINT MONO (-4275 3025);
DISPLAY INVISIBLE (-4275 3025);
FORCEPROP 2 LAST CDS_LOCATION C966
J 0
(-4225 3225);
DISPLAY 1.021277 (-4225 3225);
DISPLAY INVISIBLE (-4225 3225);
FORCEPROP 2 LAST $SEC 1
J 0
(-4225 3225);
DISPLAY 0.680851 (-4225 3225);
PAINT MONO (-4225 3225);
DISPLAY INVISIBLE (-4225 3225);
FORCEPROP 2 LAST CDS_SEC 1
J 0
(-4225 3225);
DISPLAY 1.021277 (-4225 3225);
DISPLAY INVISIBLE (-4225 3225);
FORCEPROP 1 LAST PATH I27
J 0
(-4225 3175);
DISPLAY 0.978723 (-4225 3175);
PAINT WHITE (-4225 3175);
DISPLAY INVISIBLE (-4225 3175);
FORCEADD Q_CAP..1
(-3800 1500);
FORCEPROP 1 LAST PART_NUMBER CH6101MEB03
J 0
(-3750 1350);
DISPLAY 0.638298 (-3750 1350);
DISPLAY INVISIBLE (-3750 1350);
FORCEPROP 1 LAST MATERIAL X6S
J 0
(-3750 1400);
DISPLAY 0.638298 (-3750 1400);
FORCEPROP 1 LAST PACK_TYPE C0402
J 0
(-3750 1300);
DISPLAY 0.638298 (-3750 1300);
FORCEPROP 1 LAST TOLERANCE 20%
J 0
(-3750 1450);
DISPLAY 0.638298 (-3750 1450);
FORCEPROP 1 LAST VALUE 10UF
J 0
(-3750 1550);
DISPLAY 0.638298 (-3750 1550);
FORCEPROP 1 LAST VOLTAGE 6.3V
J 0
(-3750 1500);
DISPLAY 0.638298 (-3750 1500);
FORCEPROP 1 LAST $LOCATION C972
J 0
(-3750 1600);
DISPLAY 0.638298 (-3750 1600);
FORCEPROP 1 LASTPIN (-3800 1600) $PN 1
J 0
(-3790 1580);
DISPLAY 0.787234 (-3790 1580);
FORCEPROP 1 LASTPIN (-3800 1400) $PN 2
J 0
(-3790 1380);
DISPLAY 0.787234 (-3790 1380);
FORCEPROP 2 LAST CDS_LIB pure_quanta
J 0
(-3800 1500);
PAINT MONO (-3800 1500);
DISPLAY INVISIBLE (-3800 1500);
FORCEPROP 2 LAST CDS_LOCATION C972
J 0
(-3750 1700);
DISPLAY 1.021277 (-3750 1700);
DISPLAY INVISIBLE (-3750 1700);
FORCEPROP 2 LAST $SEC 1
J 0
(-3750 1700);
DISPLAY 0.680851 (-3750 1700);
PAINT MONO (-3750 1700);
DISPLAY INVISIBLE (-3750 1700);
FORCEPROP 2 LAST CDS_SEC 1
J 0
(-3750 1700);
DISPLAY 1.021277 (-3750 1700);
DISPLAY INVISIBLE (-3750 1700);
FORCEPROP 1 LAST PATH I28
J 0
(-3750 1650);
DISPLAY 0.978723 (-3750 1650);
PAINT WHITE (-3750 1650);
DISPLAY INVISIBLE (-3750 1650);
FORCEADD Q_CAP..1
(-3350 1500);
FORCEPROP 1 LAST PART_NUMBER CH6101MEB03
J 0
(-3300 1350);
DISPLAY 0.638298 (-3300 1350);
DISPLAY INVISIBLE (-3300 1350);
FORCEPROP 1 LAST MATERIAL X6S
J 0
(-3300 1400);
DISPLAY 0.638298 (-3300 1400);
FORCEPROP 1 LAST TOLERANCE 20%
J 0
(-3300 1450);
DISPLAY 0.638298 (-3300 1450);
FORCEPROP 1 LAST VALUE 10UF
J 0
(-3300 1550);
DISPLAY 0.638298 (-3300 1550);
FORCEPROP 1 LAST VOLTAGE 6.3V
J 0
(-3300 1500);
DISPLAY 0.638298 (-3300 1500);
FORCEPROP 1 LAST PACK_TYPE C0402
J 0
(-3300 1300);
DISPLAY 0.638298 (-3300 1300);
FORCEPROP 1 LAST $LOCATION C976
J 0
(-3300 1600);
DISPLAY 0.638298 (-3300 1600);
FORCEPROP 1 LASTPIN (-3350 1600) $PN 1
J 0
(-3340 1580);
DISPLAY 0.787234 (-3340 1580);
FORCEPROP 1 LASTPIN (-3350 1400) $PN 2
J 0
(-3340 1380);
DISPLAY 0.787234 (-3340 1380);
FORCEPROP 2 LAST CDS_LIB pure_quanta
J 0
(-3350 1500);
PAINT MONO (-3350 1500);
DISPLAY INVISIBLE (-3350 1500);
FORCEPROP 2 LAST CDS_LOCATION C976
J 0
(-3300 1700);
DISPLAY 1.021277 (-3300 1700);
DISPLAY INVISIBLE (-3300 1700);
FORCEPROP 2 LAST $SEC 1
J 0
(-3300 1700);
DISPLAY 0.680851 (-3300 1700);
PAINT MONO (-3300 1700);
DISPLAY INVISIBLE (-3300 1700);
FORCEPROP 2 LAST CDS_SEC 1
J 0
(-3300 1700);
DISPLAY 1.021277 (-3300 1700);
DISPLAY INVISIBLE (-3300 1700);
FORCEPROP 1 LAST PATH I29
J 0
(-3300 1650);
DISPLAY 0.978723 (-3300 1650);
PAINT WHITE (-3300 1650);
DISPLAY INVISIBLE (-3300 1650);
FORCEADD Q_CAP..1
(-3800 -1650);
FORCEPROP 1 LAST PART_NUMBER CH622KMEB01
J 0
(-3750 -1800);
DISPLAY 0.638298 (-3750 -1800);
DISPLAY INVISIBLE (-3750 -1800);
FORCEPROP 1 LAST PACK_TYPE C0402
J 0
(-3750 -1850);
DISPLAY 0.638298 (-3750 -1850);
FORCEPROP 1 LAST MATERIAL X6S
J 0
(-3750 -1750);
DISPLAY 0.638298 (-3750 -1750);
FORCEPROP 1 LAST VALUE 22UF
J 0
(-3750 -1600);
DISPLAY 0.638298 (-3750 -1600);
FORCEPROP 1 LAST TOLERANCE 20%
J 0
(-3750 -1700);
DISPLAY 0.638298 (-3750 -1700);
FORCEPROP 1 LAST VOLTAGE 4V
J 0
(-3750 -1650);
DISPLAY 0.638298 (-3750 -1650);
FORCEPROP 1 LAST $LOCATION C402
J 0
(-3750 -1550);
DISPLAY 0.978723 (-3750 -1550);
FORCEPROP 1 LASTPIN (-3800 -1550) $PN 1
J 0
(-3790 -1570);
DISPLAY 0.787234 (-3790 -1570);
FORCEPROP 1 LASTPIN (-3800 -1750) $PN 2
J 0
(-3790 -1770);
DISPLAY 0.787234 (-3790 -1770);
FORCEPROP 2 LAST CDS_LIB pure_quanta
J 0
(-3800 -1650);
PAINT MONO (-3800 -1650);
DISPLAY INVISIBLE (-3800 -1650);
FORCEPROP 2 LAST CDS_LOCATION C402
J 0
(-3750 -1450);
DISPLAY 1.021277 (-3750 -1450);
DISPLAY INVISIBLE (-3750 -1450);
FORCEPROP 2 LAST $SEC 1
J 0
(-3750 -1450);
DISPLAY 0.680851 (-3750 -1450);
PAINT MONO (-3750 -1450);
DISPLAY INVISIBLE (-3750 -1450);
FORCEPROP 2 LAST CDS_SEC 1
J 0
(-3750 -1450);
DISPLAY 1.021277 (-3750 -1450);
DISPLAY INVISIBLE (-3750 -1450);
FORCEPROP 1 LAST PATH I3
J 0
(-3750 -1500);
DISPLAY 0.978723 (-3750 -1500);
PAINT WHITE (-3750 -1500);
DISPLAY INVISIBLE (-3750 -1500);
FORCEADD Q_CAP..1
(-3825 2250);
FORCEPROP 1 LAST PART_NUMBER CH6101MEB03
J 0
(-3775 2100);
DISPLAY 0.638298 (-3775 2100);
DISPLAY INVISIBLE (-3775 2100);
FORCEPROP 1 LAST PACK_TYPE C0402
J 0
(-3775 2050);
DISPLAY 0.638298 (-3775 2050);
FORCEPROP 1 LAST MATERIAL X6S
J 0
(-3775 2150);
DISPLAY 0.638298 (-3775 2150);
FORCEPROP 1 LAST TOLERANCE 20%
J 0
(-3775 2200);
DISPLAY 0.638298 (-3775 2200);
FORCEPROP 1 LAST VALUE 10UF
J 0
(-3775 2300);
DISPLAY 0.638298 (-3775 2300);
FORCEPROP 1 LAST VOLTAGE 6.3V
J 0
(-3775 2250);
DISPLAY 0.638298 (-3775 2250);
FORCEPROP 1 LAST $LOCATION C971
J 0
(-3775 2350);
DISPLAY 0.638298 (-3775 2350);
FORCEPROP 1 LASTPIN (-3825 2350) $PN 1
J 0
(-3815 2330);
DISPLAY 0.787234 (-3815 2330);
FORCEPROP 1 LASTPIN (-3825 2150) $PN 2
J 0
(-3815 2130);
DISPLAY 0.787234 (-3815 2130);
FORCEPROP 2 LAST CDS_LIB pure_quanta
J 0
(-3825 2250);
PAINT MONO (-3825 2250);
DISPLAY INVISIBLE (-3825 2250);
FORCEPROP 2 LAST CDS_LOCATION C971
J 0
(-3775 2450);
DISPLAY 1.021277 (-3775 2450);
DISPLAY INVISIBLE (-3775 2450);
FORCEPROP 2 LAST $SEC 1
J 0
(-3775 2450);
DISPLAY 0.680851 (-3775 2450);
PAINT MONO (-3775 2450);
DISPLAY INVISIBLE (-3775 2450);
FORCEPROP 2 LAST CDS_SEC 1
J 0
(-3775 2450);
DISPLAY 1.021277 (-3775 2450);
DISPLAY INVISIBLE (-3775 2450);
FORCEPROP 1 LAST PATH I30
J 0
(-3775 2400);
DISPLAY 0.978723 (-3775 2400);
PAINT WHITE (-3775 2400);
DISPLAY INVISIBLE (-3775 2400);
FORCEADD Q_CAP..1
(-3825 3025);
FORCEPROP 1 LAST PART_NUMBER CH6101MEB03
J 0
(-3775 2875);
DISPLAY 0.638298 (-3775 2875);
DISPLAY INVISIBLE (-3775 2875);
FORCEPROP 1 LAST PACK_TYPE C0402
J 0
(-3775 2825);
DISPLAY 0.638298 (-3775 2825);
FORCEPROP 1 LAST MATERIAL X6S
J 0
(-3775 2925);
DISPLAY 0.638298 (-3775 2925);
FORCEPROP 1 LAST TOLERANCE 20%
J 0
(-3775 2975);
DISPLAY 0.638298 (-3775 2975);
FORCEPROP 1 LAST VALUE 10UF
J 0
(-3775 3075);
DISPLAY 0.638298 (-3775 3075);
FORCEPROP 1 LAST VOLTAGE 6.3V
J 0
(-3775 3025);
DISPLAY 0.638298 (-3775 3025);
FORCEPROP 1 LAST $LOCATION C970
J 0
(-3775 3125);
DISPLAY 0.638298 (-3775 3125);
FORCEPROP 1 LASTPIN (-3825 3125) $PN 1
J 0
(-3815 3105);
DISPLAY 0.787234 (-3815 3105);
FORCEPROP 1 LASTPIN (-3825 2925) $PN 2
J 0
(-3815 2905);
DISPLAY 0.787234 (-3815 2905);
FORCEPROP 2 LAST CDS_LIB pure_quanta
J 0
(-3825 3025);
PAINT MONO (-3825 3025);
DISPLAY INVISIBLE (-3825 3025);
FORCEPROP 2 LAST CDS_LOCATION C970
J 0
(-3775 3225);
DISPLAY 1.021277 (-3775 3225);
DISPLAY INVISIBLE (-3775 3225);
FORCEPROP 2 LAST $SEC 1
J 0
(-3775 3225);
DISPLAY 0.680851 (-3775 3225);
PAINT MONO (-3775 3225);
DISPLAY INVISIBLE (-3775 3225);
FORCEPROP 2 LAST CDS_SEC 1
J 0
(-3775 3225);
DISPLAY 1.021277 (-3775 3225);
DISPLAY INVISIBLE (-3775 3225);
FORCEPROP 1 LAST PATH I31
J 0
(-3775 3175);
DISPLAY 0.978723 (-3775 3175);
PAINT WHITE (-3775 3175);
DISPLAY INVISIBLE (-3775 3175);
FORCEADD Q_CAP..1
(-3375 2250);
FORCEPROP 1 LAST PART_NUMBER CH6101MEB03
J 0
(-3325 2100);
DISPLAY 0.638298 (-3325 2100);
DISPLAY INVISIBLE (-3325 2100);
FORCEPROP 1 LAST PACK_TYPE C0402
J 0
(-3325 2050);
DISPLAY 0.638298 (-3325 2050);
FORCEPROP 1 LAST MATERIAL X6S
J 0
(-3325 2150);
DISPLAY 0.638298 (-3325 2150);
FORCEPROP 1 LAST TOLERANCE 20%
J 0
(-3325 2200);
DISPLAY 0.638298 (-3325 2200);
FORCEPROP 1 LAST VALUE 10UF
J 0
(-3325 2300);
DISPLAY 0.638298 (-3325 2300);
FORCEPROP 1 LAST VOLTAGE 6.3V
J 0
(-3325 2250);
DISPLAY 0.638298 (-3325 2250);
FORCEPROP 1 LAST $LOCATION C975
J 0
(-3325 2350);
DISPLAY 0.638298 (-3325 2350);
FORCEPROP 1 LASTPIN (-3375 2350) $PN 1
J 0
(-3365 2330);
DISPLAY 0.787234 (-3365 2330);
FORCEPROP 1 LASTPIN (-3375 2150) $PN 2
J 0
(-3365 2130);
DISPLAY 0.787234 (-3365 2130);
FORCEPROP 2 LAST CDS_LIB pure_quanta
J 0
(-3375 2250);
PAINT MONO (-3375 2250);
DISPLAY INVISIBLE (-3375 2250);
FORCEPROP 2 LAST CDS_LOCATION C975
J 0
(-3325 2450);
DISPLAY 1.021277 (-3325 2450);
DISPLAY INVISIBLE (-3325 2450);
FORCEPROP 2 LAST $SEC 1
J 0
(-3325 2450);
DISPLAY 0.680851 (-3325 2450);
PAINT MONO (-3325 2450);
DISPLAY INVISIBLE (-3325 2450);
FORCEPROP 2 LAST CDS_SEC 1
J 0
(-3325 2450);
DISPLAY 1.021277 (-3325 2450);
DISPLAY INVISIBLE (-3325 2450);
FORCEPROP 1 LAST PATH I32
J 0
(-3325 2400);
DISPLAY 0.978723 (-3325 2400);
PAINT WHITE (-3325 2400);
DISPLAY INVISIBLE (-3325 2400);
FORCEADD Q_CAP..1
(-3375 3025);
FORCEPROP 1 LAST PART_NUMBER CH6101MEB03
J 0
(-3325 2875);
DISPLAY 0.638298 (-3325 2875);
DISPLAY INVISIBLE (-3325 2875);
FORCEPROP 1 LAST PACK_TYPE C0402
J 0
(-3325 2825);
DISPLAY 0.638298 (-3325 2825);
FORCEPROP 1 LAST MATERIAL X6S
J 0
(-3325 2925);
DISPLAY 0.638298 (-3325 2925);
FORCEPROP 1 LAST TOLERANCE 20%
J 0
(-3325 2975);
DISPLAY 0.638298 (-3325 2975);
FORCEPROP 1 LAST VALUE 10UF
J 0
(-3325 3075);
DISPLAY 0.638298 (-3325 3075);
FORCEPROP 1 LAST VOLTAGE 6.3V
J 0
(-3325 3025);
DISPLAY 0.638298 (-3325 3025);
FORCEPROP 1 LAST $LOCATION C974
J 0
(-3325 3125);
DISPLAY 0.638298 (-3325 3125);
FORCEPROP 1 LASTPIN (-3375 3125) $PN 1
J 0
(-3365 3105);
DISPLAY 0.787234 (-3365 3105);
FORCEPROP 1 LASTPIN (-3375 2925) $PN 2
J 0
(-3365 2905);
DISPLAY 0.787234 (-3365 2905);
FORCEPROP 2 LAST CDS_LIB pure_quanta
J 0
(-3375 3025);
PAINT MONO (-3375 3025);
DISPLAY INVISIBLE (-3375 3025);
FORCEPROP 2 LAST CDS_LOCATION C974
J 0
(-3325 3225);
DISPLAY 1.021277 (-3325 3225);
DISPLAY INVISIBLE (-3325 3225);
FORCEPROP 2 LAST $SEC 1
J 0
(-3325 3225);
DISPLAY 0.680851 (-3325 3225);
PAINT MONO (-3325 3225);
DISPLAY INVISIBLE (-3325 3225);
FORCEPROP 2 LAST CDS_SEC 1
J 0
(-3325 3225);
DISPLAY 1.021277 (-3325 3225);
DISPLAY INVISIBLE (-3325 3225);
FORCEPROP 1 LAST PATH I33
J 0
(-3325 3175);
DISPLAY 0.978723 (-3325 3175);
PAINT WHITE (-3325 3175);
DISPLAY INVISIBLE (-3325 3175);
FORCEADD Q_CAP..1
(-2900 -850);
FORCEPROP 1 LAST PART_NUMBER CH622KMEB01
J 0
(-2850 -1000);
DISPLAY 0.638298 (-2850 -1000);
DISPLAY INVISIBLE (-2850 -1000);
FORCEPROP 1 LAST PACK_TYPE C0402
J 0
(-2850 -1050);
DISPLAY 0.638298 (-2850 -1050);
FORCEPROP 1 LAST VOLTAGE 4V
J 0
(-2850 -850);
DISPLAY 0.638298 (-2850 -850);
FORCEPROP 1 LAST VALUE 22UF
J 0
(-2850 -800);
DISPLAY 0.638298 (-2850 -800);
FORCEPROP 1 LAST MATERIAL X6S
J 0
(-2850 -950);
DISPLAY 0.638298 (-2850 -950);
FORCEPROP 1 LAST TOLERANCE 20%
J 0
(-2850 -900);
DISPLAY 0.638298 (-2850 -900);
FORCEPROP 1 LAST $LOCATION C405
J 0
(-2850 -750);
DISPLAY 0.978723 (-2850 -750);
FORCEPROP 1 LASTPIN (-2900 -750) $PN 1
J 0
(-2890 -770);
DISPLAY 0.787234 (-2890 -770);
FORCEPROP 1 LASTPIN (-2900 -950) $PN 2
J 0
(-2890 -970);
DISPLAY 0.787234 (-2890 -970);
FORCEPROP 2 LAST CDS_LIB pure_quanta
J 0
(-2900 -850);
PAINT MONO (-2900 -850);
DISPLAY INVISIBLE (-2900 -850);
FORCEPROP 2 LAST CDS_LOCATION C405
J 0
(-2850 -650);
DISPLAY 1.021277 (-2850 -650);
DISPLAY INVISIBLE (-2850 -650);
FORCEPROP 2 LAST $SEC 1
J 0
(-2850 -650);
DISPLAY 0.680851 (-2850 -650);
PAINT MONO (-2850 -650);
DISPLAY INVISIBLE (-2850 -650);
FORCEPROP 2 LAST CDS_SEC 1
J 0
(-2850 -650);
DISPLAY 1.021277 (-2850 -650);
DISPLAY INVISIBLE (-2850 -650);
FORCEPROP 1 LAST PATH I34
J 0
(-2850 -700);
DISPLAY 0.978723 (-2850 -700);
PAINT WHITE (-2850 -700);
DISPLAY INVISIBLE (-2850 -700);
FORCEADD Q_CAP..1
(-2900 -50);
FORCEPROP 1 LAST PART_NUMBER CH647KMEA04
J 0
(-2850 -200);
DISPLAY 0.638298 (-2850 -200);
DISPLAY INVISIBLE (-2850 -200);
FORCEPROP 1 LAST MATERIAL X6S
J 0
(-2850 -150);
DISPLAY 0.638298 (-2850 -150);
FORCEPROP 1 LAST PACK_TYPE C0805
J 0
(-2850 -250);
DISPLAY 0.638298 (-2850 -250);
FORCEPROP 1 LAST VOLTAGE 4V
J 0
(-2850 -50);
DISPLAY 0.638298 (-2850 -50);
FORCEPROP 1 LAST TOLERANCE 20%
J 0
(-2850 -100);
DISPLAY 0.638298 (-2850 -100);
FORCEPROP 1 LAST VALUE 47UF
J 0
(-2850 0);
DISPLAY 0.638298 (-2850 0);
FORCEPROP 1 LAST $LOCATION C214
J 0
(-2850 50);
DISPLAY 0.638298 (-2850 50);
FORCEPROP 1 LASTPIN (-2900 50) $PN 1
J 0
(-2890 30);
DISPLAY 0.787234 (-2890 30);
FORCEPROP 1 LASTPIN (-2900 -150) $PN 2
J 0
(-2890 -170);
DISPLAY 0.787234 (-2890 -170);
FORCEPROP 2 LAST CDS_LIB pure_quanta
J 0
(-2900 -50);
PAINT MONO (-2900 -50);
DISPLAY INVISIBLE (-2900 -50);
FORCEPROP 1 LAST $LOCATION C214
J 0
(-2850 150);
DISPLAY 1.021277 (-2850 150);
DISPLAY INVISIBLE (-2850 150);
FORCEPROP 2 LAST CDS_LOCATION C214
J 0
(-2850 150);
DISPLAY 1.021277 (-2850 150);
DISPLAY INVISIBLE (-2850 150);
FORCEPROP 2 LAST $SEC 1
J 0
(-2850 150);
DISPLAY 0.680851 (-2850 150);
PAINT MONO (-2850 150);
DISPLAY INVISIBLE (-2850 150);
FORCEPROP 2 LAST CDS_SEC 1
J 0
(-2850 150);
DISPLAY 1.021277 (-2850 150);
DISPLAY INVISIBLE (-2850 150);
FORCEPROP 1 LAST PATH I35
J 0
(-2850 100);
DISPLAY 0.978723 (-2850 100);
PAINT WHITE (-2850 100);
DISPLAY INVISIBLE (-2850 100);
FORCEADD Q_CAP..1
(-2450 -50);
FORCEPROP 1 LAST PART_NUMBER CH647KMEA04
J 0
(-2400 -200);
DISPLAY 0.638298 (-2400 -200);
DISPLAY INVISIBLE (-2400 -200);
FORCEPROP 1 LAST MATERIAL X6S
J 0
(-2400 -150);
DISPLAY 0.638298 (-2400 -150);
FORCEPROP 1 LAST PACK_TYPE C0805
J 0
(-2400 -250);
DISPLAY 0.638298 (-2400 -250);
FORCEPROP 1 LAST TOLERANCE 20%
J 0
(-2400 -100);
DISPLAY 0.638298 (-2400 -100);
FORCEPROP 1 LAST VOLTAGE 4V
J 0
(-2400 -50);
DISPLAY 0.638298 (-2400 -50);
FORCEPROP 1 LAST VALUE 47UF
J 0
(-2400 0);
DISPLAY 0.638298 (-2400 0);
FORCEPROP 1 LAST $LOCATION C215
J 0
(-2400 50);
DISPLAY 0.638298 (-2400 50);
FORCEPROP 1 LASTPIN (-2450 50) $PN 1
J 0
(-2440 30);
DISPLAY 0.787234 (-2440 30);
FORCEPROP 1 LASTPIN (-2450 -150) $PN 2
J 0
(-2440 -170);
DISPLAY 0.787234 (-2440 -170);
FORCEPROP 2 LAST CDS_LIB pure_quanta
J 0
(-2450 -50);
PAINT MONO (-2450 -50);
DISPLAY INVISIBLE (-2450 -50);
FORCEPROP 1 LAST $LOCATION C215
J 0
(-2400 150);
DISPLAY 1.021277 (-2400 150);
DISPLAY INVISIBLE (-2400 150);
FORCEPROP 2 LAST CDS_LOCATION C215
J 0
(-2400 150);
DISPLAY 1.021277 (-2400 150);
DISPLAY INVISIBLE (-2400 150);
FORCEPROP 2 LAST $SEC 1
J 0
(-2400 150);
DISPLAY 0.680851 (-2400 150);
PAINT MONO (-2400 150);
DISPLAY INVISIBLE (-2400 150);
FORCEPROP 2 LAST CDS_SEC 1
J 0
(-2400 150);
DISPLAY 1.021277 (-2400 150);
DISPLAY INVISIBLE (-2400 150);
FORCEPROP 1 LAST PATH I36
J 0
(-2400 100);
DISPLAY 0.978723 (-2400 100);
PAINT WHITE (-2400 100);
DISPLAY INVISIBLE (-2400 100);
FORCEADD Q_CAP..1
(-2900 725);
FORCEPROP 1 LAST PART_NUMBER CH6101MEB03
J 0
(-2850 575);
DISPLAY 0.638298 (-2850 575);
DISPLAY INVISIBLE (-2850 575);
FORCEPROP 1 LAST VOLTAGE 6.3V
J 0
(-2850 725);
DISPLAY 0.638298 (-2850 725);
FORCEPROP 1 LAST VALUE 10UF
J 0
(-2850 775);
DISPLAY 0.638298 (-2850 775);
FORCEPROP 1 LAST PACK_TYPE C0402
J 0
(-2850 525);
DISPLAY 0.638298 (-2850 525);
FORCEPROP 1 LAST TOLERANCE 20%
J 0
(-2850 675);
DISPLAY 0.638298 (-2850 675);
FORCEPROP 1 LAST MATERIAL X6S
J 0
(-2850 625);
DISPLAY 0.638298 (-2850 625);
FORCEPROP 1 LAST $LOCATION C981
J 0
(-2850 825);
DISPLAY 0.638298 (-2850 825);
FORCEPROP 1 LASTPIN (-2900 825) $PN 1
J 0
(-2890 805);
DISPLAY 0.787234 (-2890 805);
FORCEPROP 1 LASTPIN (-2900 625) $PN 2
J 0
(-2890 605);
DISPLAY 0.787234 (-2890 605);
FORCEPROP 2 LAST CDS_LIB pure_quanta
J 0
(-2900 725);
PAINT MONO (-2900 725);
DISPLAY INVISIBLE (-2900 725);
FORCEPROP 2 LAST CDS_LOCATION C981
J 0
(-2850 925);
DISPLAY 1.021277 (-2850 925);
DISPLAY INVISIBLE (-2850 925);
FORCEPROP 2 LAST $SEC 1
J 0
(-2850 925);
DISPLAY 0.680851 (-2850 925);
PAINT MONO (-2850 925);
DISPLAY INVISIBLE (-2850 925);
FORCEPROP 2 LAST CDS_SEC 1
J 0
(-2850 925);
DISPLAY 1.021277 (-2850 925);
DISPLAY INVISIBLE (-2850 925);
FORCEPROP 1 LAST PATH I37
J 0
(-2850 875);
DISPLAY 0.978723 (-2850 875);
PAINT WHITE (-2850 875);
DISPLAY INVISIBLE (-2850 875);
FORCEADD Q_CAP..1
(-2450 725);
FORCEPROP 1 LAST PART_NUMBER CH6101MEB03
J 0
(-2400 575);
DISPLAY 0.638298 (-2400 575);
DISPLAY INVISIBLE (-2400 575);
FORCEPROP 1 LAST VOLTAGE 6.3V
J 0
(-2400 725);
DISPLAY 0.638298 (-2400 725);
FORCEPROP 1 LAST VALUE 10UF
J 0
(-2400 775);
DISPLAY 0.638298 (-2400 775);
FORCEPROP 1 LAST TOLERANCE 20%
J 0
(-2400 675);
DISPLAY 0.638298 (-2400 675);
FORCEPROP 1 LAST PACK_TYPE C0402
J 0
(-2400 525);
DISPLAY 0.638298 (-2400 525);
FORCEPROP 1 LAST MATERIAL X6S
J 0
(-2400 625);
DISPLAY 0.638298 (-2400 625);
FORCEPROP 1 LAST $LOCATION C985
J 0
(-2400 825);
DISPLAY 0.638298 (-2400 825);
FORCEPROP 1 LASTPIN (-2450 825) $PN 1
J 0
(-2440 805);
DISPLAY 0.787234 (-2440 805);
FORCEPROP 1 LASTPIN (-2450 625) $PN 2
J 0
(-2440 605);
DISPLAY 0.787234 (-2440 605);
FORCEPROP 2 LAST CDS_LIB pure_quanta
J 0
(-2450 725);
PAINT MONO (-2450 725);
DISPLAY INVISIBLE (-2450 725);
FORCEPROP 2 LAST CDS_LOCATION C985
J 0
(-2400 925);
DISPLAY 1.021277 (-2400 925);
DISPLAY INVISIBLE (-2400 925);
FORCEPROP 2 LAST $SEC 1
J 0
(-2400 925);
DISPLAY 0.680851 (-2400 925);
PAINT MONO (-2400 925);
DISPLAY INVISIBLE (-2400 925);
FORCEPROP 2 LAST CDS_SEC 1
J 0
(-2400 925);
DISPLAY 1.021277 (-2400 925);
DISPLAY INVISIBLE (-2400 925);
FORCEPROP 1 LAST PATH I38
J 0
(-2400 875);
DISPLAY 0.978723 (-2400 875);
PAINT WHITE (-2400 875);
DISPLAY INVISIBLE (-2400 875);
FORCEADD UNIVERSAL_POWER..1
(-2000 -575);
FORCEPROP 3 LASTPIN (-2000 -625) SIG_NAME PVCCINFAON_CPU0\g
J 0
(-1990 -615);
DISPLAY 0.659574 (-1990 -615);
PAINT MONO (-1990 -615);
DISPLAY INVISIBLE (-1990 -615);
FORCEPROP 1 LAST HDL_POWER PVCCINFAON_CPU0
J 1
(-1750 -525);
DISPLAY 0.872340 (-1750 -525);
PAINT GREEN (-1750 -525);
FORCEPROP 2 LAST CDS_LIB logical_power
J 0
(-2000 -575);
PAINT MONO (-2000 -575);
DISPLAY INVISIBLE (-2000 -575);
FORCEPROP 1 LAST PATH I39
J 0
(-1950 -550);
DISPLAY 0.872340 (-1950 -550);
PAINT AQUA (-1950 -550);
DISPLAY INVISIBLE (-1950 -550);
FORCEADD Q_CAP..1
(-3350 -1650);
FORCEPROP 1 LAST PART_NUMBER CH622KMEB01
J 0
(-3300 -1800);
DISPLAY 0.638298 (-3300 -1800);
DISPLAY INVISIBLE (-3300 -1800);
FORCEPROP 1 LAST PACK_TYPE C0402
J 0
(-3300 -1850);
DISPLAY 0.638298 (-3300 -1850);
FORCEPROP 1 LAST VALUE 22UF
J 0
(-3300 -1600);
DISPLAY 0.638298 (-3300 -1600);
FORCEPROP 1 LAST MATERIAL X6S
J 0
(-3300 -1750);
DISPLAY 0.638298 (-3300 -1750);
FORCEPROP 1 LAST VOLTAGE 4V
J 0
(-3300 -1650);
DISPLAY 0.638298 (-3300 -1650);
FORCEPROP 1 LAST TOLERANCE 20%
J 0
(-3300 -1700);
DISPLAY 0.638298 (-3300 -1700);
FORCEPROP 1 LAST $LOCATION C404
J 0
(-3300 -1550);
DISPLAY 0.978723 (-3300 -1550);
FORCEPROP 1 LASTPIN (-3350 -1550) $PN 1
J 0
(-3340 -1570);
DISPLAY 0.787234 (-3340 -1570);
FORCEPROP 1 LASTPIN (-3350 -1750) $PN 2
J 0
(-3340 -1770);
DISPLAY 0.787234 (-3340 -1770);
FORCEPROP 2 LAST CDS_LIB pure_quanta
J 0
(-3350 -1650);
PAINT MONO (-3350 -1650);
DISPLAY INVISIBLE (-3350 -1650);
FORCEPROP 2 LAST CDS_LOCATION C404
J 0
(-3300 -1450);
DISPLAY 1.021277 (-3300 -1450);
DISPLAY INVISIBLE (-3300 -1450);
FORCEPROP 2 LAST $SEC 1
J 0
(-3300 -1450);
DISPLAY 0.680851 (-3300 -1450);
PAINT MONO (-3300 -1450);
DISPLAY INVISIBLE (-3300 -1450);
FORCEPROP 2 LAST CDS_SEC 1
J 0
(-3300 -1450);
DISPLAY 1.021277 (-3300 -1450);
DISPLAY INVISIBLE (-3300 -1450);
FORCEPROP 1 LAST PATH I4
J 0
(-3300 -1500);
DISPLAY 0.978723 (-3300 -1500);
PAINT WHITE (-3300 -1500);
DISPLAY INVISIBLE (-3300 -1500);
FORCEADD Q_CAP..1
(-2000 -50);
FORCEPROP 1 LAST PART_NUMBER CH647KMEA04
J 0
(-1950 -200);
DISPLAY 0.638298 (-1950 -200);
DISPLAY INVISIBLE (-1950 -200);
FORCEPROP 1 LAST MATERIAL X6S
J 0
(-1950 -150);
DISPLAY 0.638298 (-1950 -150);
FORCEPROP 1 LAST VOLTAGE 4V
J 0
(-1950 -50);
DISPLAY 0.638298 (-1950 -50);
FORCEPROP 1 LAST TOLERANCE 20%
J 0
(-1950 -100);
DISPLAY 0.638298 (-1950 -100);
FORCEPROP 1 LAST VALUE 47UF
J 0
(-1950 0);
DISPLAY 0.638298 (-1950 0);
FORCEPROP 1 LAST PACK_TYPE C0805
J 0
(-1950 -250);
DISPLAY 0.638298 (-1950 -250);
FORCEPROP 1 LAST $LOCATION C216
J 0
(-1950 50);
DISPLAY 0.638298 (-1950 50);
FORCEPROP 1 LASTPIN (-2000 50) $PN 1
J 0
(-1990 30);
DISPLAY 0.787234 (-1990 30);
FORCEPROP 1 LASTPIN (-2000 -150) $PN 2
J 0
(-1990 -170);
DISPLAY 0.787234 (-1990 -170);
FORCEPROP 2 LAST CDS_LIB pure_quanta
J 0
(-2000 -50);
PAINT MONO (-2000 -50);
DISPLAY INVISIBLE (-2000 -50);
FORCEPROP 1 LAST $LOCATION C216
J 0
(-1950 150);
DISPLAY 1.021277 (-1950 150);
DISPLAY INVISIBLE (-1950 150);
FORCEPROP 2 LAST CDS_LOCATION C216
J 0
(-1950 150);
DISPLAY 1.021277 (-1950 150);
DISPLAY INVISIBLE (-1950 150);
FORCEPROP 2 LAST $SEC 1
J 0
(-1950 150);
DISPLAY 0.680851 (-1950 150);
PAINT MONO (-1950 150);
DISPLAY INVISIBLE (-1950 150);
FORCEPROP 2 LAST CDS_SEC 1
J 0
(-1950 150);
DISPLAY 1.021277 (-1950 150);
DISPLAY INVISIBLE (-1950 150);
FORCEPROP 1 LAST PATH I40
J 0
(-1950 100);
DISPLAY 0.978723 (-1950 100);
PAINT WHITE (-1950 100);
DISPLAY INVISIBLE (-1950 100);
FORCEADD Q_CAP..1
(-1550 -850);
FORCEPROP 1 LAST PART_NUMBER CH622KMEB01
J 0
(-1500 -1000);
DISPLAY 0.638298 (-1500 -1000);
DISPLAY INVISIBLE (-1500 -1000);
FORCEPROP 1 LAST PACK_TYPE C0402
J 0
(-1500 -1050);
DISPLAY 0.638298 (-1500 -1050);
FORCEPROP 1 LAST MATERIAL X6S
J 0
(-1500 -950);
DISPLAY 0.638298 (-1500 -950);
FORCEPROP 1 LAST TOLERANCE 20%
J 0
(-1500 -900);
DISPLAY 0.638298 (-1500 -900);
FORCEPROP 1 LAST VOLTAGE 4V
J 0
(-1500 -850);
DISPLAY 0.638298 (-1500 -850);
FORCEPROP 1 LAST VALUE 22UF
J 0
(-1500 -800);
DISPLAY 0.638298 (-1500 -800);
FORCEPROP 1 LAST $LOCATION C410
J 0
(-1500 -750);
DISPLAY 0.978723 (-1500 -750);
FORCEPROP 1 LASTPIN (-1550 -750) $PN 1
J 0
(-1540 -770);
DISPLAY 0.787234 (-1540 -770);
FORCEPROP 1 LASTPIN (-1550 -950) $PN 2
J 0
(-1540 -970);
DISPLAY 0.787234 (-1540 -970);
FORCEPROP 2 LAST CDS_LIB pure_quanta
J 0
(-1550 -850);
PAINT MONO (-1550 -850);
DISPLAY INVISIBLE (-1550 -850);
FORCEPROP 2 LAST CDS_LOCATION C410
J 0
(-1500 -650);
DISPLAY 1.021277 (-1500 -650);
DISPLAY INVISIBLE (-1500 -650);
FORCEPROP 2 LAST $SEC 1
J 0
(-1500 -650);
DISPLAY 0.680851 (-1500 -650);
PAINT MONO (-1500 -650);
DISPLAY INVISIBLE (-1500 -650);
FORCEPROP 2 LAST CDS_SEC 1
J 0
(-1500 -650);
DISPLAY 1.021277 (-1500 -650);
DISPLAY INVISIBLE (-1500 -650);
FORCEPROP 1 LAST PATH I41
J 0
(-1500 -700);
DISPLAY 0.978723 (-1500 -700);
PAINT WHITE (-1500 -700);
DISPLAY INVISIBLE (-1500 -700);
FORCEADD Q_CAP..1
(-1100 -850);
FORCEPROP 1 LAST PART_NUMBER CH622KMEB01
J 0
(-1050 -1000);
DISPLAY 0.638298 (-1050 -1000);
DISPLAY INVISIBLE (-1050 -1000);
FORCEPROP 1 LAST PACK_TYPE C0402
J 0
(-1050 -1050);
DISPLAY 0.638298 (-1050 -1050);
FORCEPROP 1 LAST MATERIAL X6S
J 0
(-1050 -950);
DISPLAY 0.638298 (-1050 -950);
FORCEPROP 1 LAST VOLTAGE 4V
J 0
(-1050 -850);
DISPLAY 0.638298 (-1050 -850);
FORCEPROP 1 LAST TOLERANCE 20%
J 0
(-1050 -900);
DISPLAY 0.638298 (-1050 -900);
FORCEPROP 1 LAST VALUE 22UF
J 0
(-1050 -800);
DISPLAY 0.638298 (-1050 -800);
FORCEPROP 1 LAST $LOCATION C412
J 0
(-1050 -750);
DISPLAY 0.978723 (-1050 -750);
FORCEPROP 1 LASTPIN (-1100 -750) $PN 1
J 0
(-1090 -770);
DISPLAY 0.787234 (-1090 -770);
FORCEPROP 1 LASTPIN (-1100 -950) $PN 2
J 0
(-1090 -970);
DISPLAY 0.787234 (-1090 -970);
FORCEPROP 2 LAST CDS_LIB pure_quanta
J 0
(-1100 -850);
PAINT MONO (-1100 -850);
DISPLAY INVISIBLE (-1100 -850);
FORCEPROP 2 LAST CDS_LOCATION C412
J 0
(-1050 -650);
DISPLAY 1.021277 (-1050 -650);
DISPLAY INVISIBLE (-1050 -650);
FORCEPROP 2 LAST $SEC 1
J 0
(-1050 -650);
DISPLAY 0.680851 (-1050 -650);
PAINT MONO (-1050 -650);
DISPLAY INVISIBLE (-1050 -650);
FORCEPROP 2 LAST CDS_SEC 1
J 0
(-1050 -650);
DISPLAY 1.021277 (-1050 -650);
DISPLAY INVISIBLE (-1050 -650);
FORCEPROP 1 LAST PATH I42
J 0
(-1050 -700);
DISPLAY 0.978723 (-1050 -700);
PAINT WHITE (-1050 -700);
DISPLAY INVISIBLE (-1050 -700);
FORCEADD Q_CAP..1
(-1550 -50);
FORCEPROP 1 LAST PART_NUMBER CH647KMEA04
J 0
(-1500 -200);
DISPLAY 0.638298 (-1500 -200);
DISPLAY INVISIBLE (-1500 -200);
FORCEPROP 1 LAST MATERIAL X6S
J 0
(-1500 -150);
DISPLAY 0.638298 (-1500 -150);
FORCEPROP 1 LAST PACK_TYPE C0805
J 0
(-1500 -250);
DISPLAY 0.638298 (-1500 -250);
FORCEPROP 1 LAST VOLTAGE 4V
J 0
(-1500 -50);
DISPLAY 0.638298 (-1500 -50);
FORCEPROP 1 LAST TOLERANCE 20%
J 0
(-1500 -100);
DISPLAY 0.638298 (-1500 -100);
FORCEPROP 1 LAST VALUE 47UF
J 0
(-1500 0);
DISPLAY 0.638298 (-1500 0);
FORCEPROP 1 LAST $LOCATION C217
J 0
(-1500 50);
DISPLAY 0.638298 (-1500 50);
FORCEPROP 1 LASTPIN (-1550 50) $PN 1
J 0
(-1540 30);
DISPLAY 0.787234 (-1540 30);
FORCEPROP 1 LASTPIN (-1550 -150) $PN 2
J 0
(-1540 -170);
DISPLAY 0.787234 (-1540 -170);
FORCEPROP 2 LAST CDS_LIB pure_quanta
J 0
(-1550 -50);
PAINT MONO (-1550 -50);
DISPLAY INVISIBLE (-1550 -50);
FORCEPROP 1 LAST $LOCATION C217
J 0
(-1500 150);
DISPLAY 1.021277 (-1500 150);
DISPLAY INVISIBLE (-1500 150);
FORCEPROP 2 LAST CDS_LOCATION C217
J 0
(-1500 150);
DISPLAY 1.021277 (-1500 150);
DISPLAY INVISIBLE (-1500 150);
FORCEPROP 2 LAST $SEC 1
J 0
(-1500 150);
DISPLAY 0.680851 (-1500 150);
PAINT MONO (-1500 150);
DISPLAY INVISIBLE (-1500 150);
FORCEPROP 2 LAST CDS_SEC 1
J 0
(-1500 150);
DISPLAY 1.021277 (-1500 150);
DISPLAY INVISIBLE (-1500 150);
FORCEPROP 1 LAST PATH I43
J 0
(-1500 100);
DISPLAY 0.978723 (-1500 100);
PAINT WHITE (-1500 100);
DISPLAY INVISIBLE (-1500 100);
FORCEADD Q_CAP..1
(-1100 -50);
FORCEPROP 1 LAST PART_NUMBER CH647KMEA04
J 0
(-1050 -200);
DISPLAY 0.638298 (-1050 -200);
DISPLAY INVISIBLE (-1050 -200);
FORCEPROP 1 LAST MATERIAL X6S
J 0
(-1050 -150);
DISPLAY 0.638298 (-1050 -150);
FORCEPROP 1 LAST PACK_TYPE C0805
J 0
(-1050 -250);
DISPLAY 0.638298 (-1050 -250);
FORCEPROP 1 LAST VOLTAGE 4V
J 0
(-1050 -50);
DISPLAY 0.638298 (-1050 -50);
FORCEPROP 1 LAST TOLERANCE 20%
J 0
(-1050 -100);
DISPLAY 0.638298 (-1050 -100);
FORCEPROP 1 LAST VALUE 47UF
J 0
(-1050 0);
DISPLAY 0.638298 (-1050 0);
FORCEPROP 1 LAST $LOCATION C218
J 0
(-1050 50);
DISPLAY 0.638298 (-1050 50);
FORCEPROP 1 LASTPIN (-1100 50) $PN 1
J 0
(-1090 30);
DISPLAY 0.787234 (-1090 30);
FORCEPROP 1 LASTPIN (-1100 -150) $PN 2
J 0
(-1090 -170);
DISPLAY 0.787234 (-1090 -170);
FORCEPROP 2 LAST CDS_LIB pure_quanta
J 0
(-1100 -50);
PAINT MONO (-1100 -50);
DISPLAY INVISIBLE (-1100 -50);
FORCEPROP 1 LAST $LOCATION C218
J 0
(-1050 150);
DISPLAY 1.021277 (-1050 150);
DISPLAY INVISIBLE (-1050 150);
FORCEPROP 2 LAST CDS_LOCATION C218
J 0
(-1050 150);
DISPLAY 1.021277 (-1050 150);
DISPLAY INVISIBLE (-1050 150);
FORCEPROP 2 LAST $SEC 1
J 0
(-1050 150);
DISPLAY 0.680851 (-1050 150);
PAINT MONO (-1050 150);
DISPLAY INVISIBLE (-1050 150);
FORCEPROP 2 LAST CDS_SEC 1
J 0
(-1050 150);
DISPLAY 1.021277 (-1050 150);
DISPLAY INVISIBLE (-1050 150);
FORCEPROP 1 LAST PATH I44
J 0
(-1050 100);
DISPLAY 0.978723 (-1050 100);
PAINT WHITE (-1050 100);
DISPLAY INVISIBLE (-1050 100);
FORCEADD Q_CAP..1
(-2000 725);
FORCEPROP 1 LAST PART_NUMBER CH6101MEB03
J 0
(-1950 575);
DISPLAY 0.638298 (-1950 575);
DISPLAY INVISIBLE (-1950 575);
FORCEPROP 1 LAST VALUE 10UF
J 0
(-1950 775);
DISPLAY 0.638298 (-1950 775);
FORCEPROP 1 LAST PACK_TYPE C0402
J 0
(-1950 525);
DISPLAY 0.638298 (-1950 525);
FORCEPROP 1 LAST MATERIAL X6S
J 0
(-1950 625);
DISPLAY 0.638298 (-1950 625);
FORCEPROP 1 LAST TOLERANCE 20%
J 0
(-1950 675);
DISPLAY 0.638298 (-1950 675);
FORCEPROP 1 LAST VOLTAGE 6.3V
J 0
(-1950 725);
DISPLAY 0.638298 (-1950 725);
FORCEPROP 1 LAST $LOCATION C989
J 0
(-1950 825);
DISPLAY 0.638298 (-1950 825);
FORCEPROP 1 LASTPIN (-2000 825) $PN 1
J 0
(-1990 805);
DISPLAY 0.787234 (-1990 805);
FORCEPROP 1 LASTPIN (-2000 625) $PN 2
J 0
(-1990 605);
DISPLAY 0.787234 (-1990 605);
FORCEPROP 2 LAST CDS_LIB pure_quanta
J 0
(-2000 725);
PAINT MONO (-2000 725);
DISPLAY INVISIBLE (-2000 725);
FORCEPROP 2 LAST CDS_LOCATION C989
J 0
(-1950 925);
DISPLAY 1.021277 (-1950 925);
DISPLAY INVISIBLE (-1950 925);
FORCEPROP 2 LAST $SEC 1
J 0
(-1950 925);
DISPLAY 0.680851 (-1950 925);
PAINT MONO (-1950 925);
DISPLAY INVISIBLE (-1950 925);
FORCEPROP 2 LAST CDS_SEC 1
J 0
(-1950 925);
DISPLAY 1.021277 (-1950 925);
DISPLAY INVISIBLE (-1950 925);
FORCEPROP 1 LAST PATH I45
J 0
(-1950 875);
DISPLAY 0.978723 (-1950 875);
PAINT WHITE (-1950 875);
DISPLAY INVISIBLE (-1950 875);
FORCEADD Q_CAP..1
(-1550 725);
FORCEPROP 1 LAST PART_NUMBER CH6101MEB03
J 0
(-1500 575);
DISPLAY 0.638298 (-1500 575);
DISPLAY INVISIBLE (-1500 575);
FORCEPROP 1 LAST VOLTAGE 6.3V
J 0
(-1500 725);
DISPLAY 0.638298 (-1500 725);
FORCEPROP 1 LAST VALUE 10UF
J 0
(-1500 775);
DISPLAY 0.638298 (-1500 775);
FORCEPROP 1 LAST PACK_TYPE C0402
J 0
(-1500 525);
DISPLAY 0.638298 (-1500 525);
FORCEPROP 1 LAST MATERIAL X6S
J 0
(-1500 625);
DISPLAY 0.638298 (-1500 625);
FORCEPROP 1 LAST TOLERANCE 20%
J 0
(-1500 675);
DISPLAY 0.638298 (-1500 675);
FORCEPROP 1 LAST $LOCATION C993
J 0
(-1500 825);
DISPLAY 0.638298 (-1500 825);
FORCEPROP 1 LASTPIN (-1550 825) $PN 1
J 0
(-1540 805);
DISPLAY 0.787234 (-1540 805);
FORCEPROP 1 LASTPIN (-1550 625) $PN 2
J 0
(-1540 605);
DISPLAY 0.787234 (-1540 605);
FORCEPROP 2 LAST CDS_LIB pure_quanta
J 0
(-1550 725);
PAINT MONO (-1550 725);
DISPLAY INVISIBLE (-1550 725);
FORCEPROP 2 LAST CDS_LOCATION C993
J 0
(-1500 925);
DISPLAY 1.021277 (-1500 925);
DISPLAY INVISIBLE (-1500 925);
FORCEPROP 2 LAST $SEC 1
J 0
(-1500 925);
DISPLAY 0.680851 (-1500 925);
PAINT MONO (-1500 925);
DISPLAY INVISIBLE (-1500 925);
FORCEPROP 2 LAST CDS_SEC 1
J 0
(-1500 925);
DISPLAY 1.021277 (-1500 925);
DISPLAY INVISIBLE (-1500 925);
FORCEPROP 1 LAST PATH I46
J 0
(-1500 875);
DISPLAY 0.978723 (-1500 875);
PAINT WHITE (-1500 875);
DISPLAY INVISIBLE (-1500 875);
FORCEADD Q_CAP..1
(-1100 725);
FORCEPROP 1 LAST PART_NUMBER CH6101MEB03
J 0
(-1050 575);
DISPLAY 0.638298 (-1050 575);
DISPLAY INVISIBLE (-1050 575);
FORCEPROP 1 LAST VOLTAGE 6.3V
J 0
(-1050 725);
DISPLAY 0.638298 (-1050 725);
FORCEPROP 1 LAST VALUE 10UF
J 0
(-1050 775);
DISPLAY 0.638298 (-1050 775);
FORCEPROP 1 LAST TOLERANCE 20%
J 0
(-1050 675);
DISPLAY 0.638298 (-1050 675);
FORCEPROP 1 LAST MATERIAL X6S
J 0
(-1050 625);
DISPLAY 0.638298 (-1050 625);
FORCEPROP 1 LAST PACK_TYPE C0402
J 0
(-1050 525);
DISPLAY 0.638298 (-1050 525);
FORCEPROP 1 LAST $LOCATION C997
J 0
(-1050 825);
DISPLAY 0.638298 (-1050 825);
FORCEPROP 1 LASTPIN (-1100 825) $PN 1
J 0
(-1090 805);
DISPLAY 0.787234 (-1090 805);
FORCEPROP 1 LASTPIN (-1100 625) $PN 2
J 0
(-1090 605);
DISPLAY 0.787234 (-1090 605);
FORCEPROP 2 LAST CDS_LIB pure_quanta
J 0
(-1100 725);
PAINT MONO (-1100 725);
DISPLAY INVISIBLE (-1100 725);
FORCEPROP 2 LAST CDS_LOCATION C997
J 0
(-1050 925);
DISPLAY 1.021277 (-1050 925);
DISPLAY INVISIBLE (-1050 925);
FORCEPROP 2 LAST $SEC 1
J 0
(-1050 925);
DISPLAY 0.680851 (-1050 925);
PAINT MONO (-1050 925);
DISPLAY INVISIBLE (-1050 925);
FORCEPROP 2 LAST CDS_SEC 1
J 0
(-1050 925);
DISPLAY 1.021277 (-1050 925);
DISPLAY INVISIBLE (-1050 925);
FORCEPROP 1 LAST PATH I47
J 0
(-1050 875);
DISPLAY 0.978723 (-1050 875);
PAINT WHITE (-1050 875);
DISPLAY INVISIBLE (-1050 875);
FORCEADD Q_CAP..1
(-2900 1500);
FORCEPROP 1 LAST PART_NUMBER CH6101MEB03
J 0
(-2850 1350);
DISPLAY 0.638298 (-2850 1350);
DISPLAY INVISIBLE (-2850 1350);
FORCEPROP 1 LAST PACK_TYPE C0402
J 0
(-2850 1300);
DISPLAY 0.638298 (-2850 1300);
FORCEPROP 1 LAST TOLERANCE 20%
J 0
(-2850 1450);
DISPLAY 0.638298 (-2850 1450);
FORCEPROP 1 LAST VALUE 10UF
J 0
(-2850 1550);
DISPLAY 0.638298 (-2850 1550);
FORCEPROP 1 LAST VOLTAGE 6.3V
J 0
(-2850 1500);
DISPLAY 0.638298 (-2850 1500);
FORCEPROP 1 LAST MATERIAL X6S
J 0
(-2850 1400);
DISPLAY 0.638298 (-2850 1400);
FORCEPROP 1 LAST $LOCATION C980
J 0
(-2850 1600);
DISPLAY 0.638298 (-2850 1600);
FORCEPROP 1 LASTPIN (-2900 1600) $PN 1
J 0
(-2890 1580);
DISPLAY 0.787234 (-2890 1580);
FORCEPROP 1 LASTPIN (-2900 1400) $PN 2
J 0
(-2890 1380);
DISPLAY 0.787234 (-2890 1380);
FORCEPROP 2 LAST CDS_LIB pure_quanta
J 0
(-2900 1500);
PAINT MONO (-2900 1500);
DISPLAY INVISIBLE (-2900 1500);
FORCEPROP 2 LAST CDS_LOCATION C980
J 0
(-2850 1700);
DISPLAY 1.021277 (-2850 1700);
DISPLAY INVISIBLE (-2850 1700);
FORCEPROP 2 LAST $SEC 1
J 0
(-2850 1700);
DISPLAY 0.680851 (-2850 1700);
PAINT MONO (-2850 1700);
DISPLAY INVISIBLE (-2850 1700);
FORCEPROP 2 LAST CDS_SEC 1
J 0
(-2850 1700);
DISPLAY 1.021277 (-2850 1700);
DISPLAY INVISIBLE (-2850 1700);
FORCEPROP 1 LAST PATH I48
J 0
(-2850 1650);
DISPLAY 0.978723 (-2850 1650);
PAINT WHITE (-2850 1650);
DISPLAY INVISIBLE (-2850 1650);
FORCEADD Q_CAP..1
(-2450 1500);
FORCEPROP 1 LAST PART_NUMBER CH6101MEB03
J 0
(-2400 1350);
DISPLAY 0.638298 (-2400 1350);
DISPLAY INVISIBLE (-2400 1350);
FORCEPROP 1 LAST PACK_TYPE C0402
J 0
(-2400 1300);
DISPLAY 0.638298 (-2400 1300);
FORCEPROP 1 LAST TOLERANCE 20%
J 0
(-2400 1450);
DISPLAY 0.638298 (-2400 1450);
FORCEPROP 1 LAST VALUE 10UF
J 0
(-2400 1550);
DISPLAY 0.638298 (-2400 1550);
FORCEPROP 1 LAST VOLTAGE 6.3V
J 0
(-2400 1500);
DISPLAY 0.638298 (-2400 1500);
FORCEPROP 1 LAST MATERIAL X6S
J 0
(-2400 1400);
DISPLAY 0.638298 (-2400 1400);
FORCEPROP 1 LAST $LOCATION C984
J 0
(-2400 1600);
DISPLAY 0.638298 (-2400 1600);
FORCEPROP 1 LASTPIN (-2450 1600) $PN 1
J 0
(-2440 1580);
DISPLAY 0.787234 (-2440 1580);
FORCEPROP 1 LASTPIN (-2450 1400) $PN 2
J 0
(-2440 1380);
DISPLAY 0.787234 (-2440 1380);
FORCEPROP 2 LAST CDS_LIB pure_quanta
J 0
(-2450 1500);
PAINT MONO (-2450 1500);
DISPLAY INVISIBLE (-2450 1500);
FORCEPROP 2 LAST CDS_LOCATION C984
J 0
(-2400 1700);
DISPLAY 1.021277 (-2400 1700);
DISPLAY INVISIBLE (-2400 1700);
FORCEPROP 2 LAST $SEC 1
J 0
(-2400 1700);
DISPLAY 0.680851 (-2400 1700);
PAINT MONO (-2400 1700);
DISPLAY INVISIBLE (-2400 1700);
FORCEPROP 2 LAST CDS_SEC 1
J 0
(-2400 1700);
DISPLAY 1.021277 (-2400 1700);
DISPLAY INVISIBLE (-2400 1700);
FORCEPROP 1 LAST PATH I49
J 0
(-2400 1650);
DISPLAY 0.978723 (-2400 1650);
PAINT WHITE (-2400 1650);
DISPLAY INVISIBLE (-2400 1650);
FORCEADD Q_CAP..1
(-2900 -1650);
FORCEPROP 1 LAST PART_NUMBER CH622KMEB01
J 0
(-2850 -1800);
DISPLAY 0.638298 (-2850 -1800);
DISPLAY INVISIBLE (-2850 -1800);
FORCEPROP 1 LAST VALUE 22UF
J 0
(-2850 -1600);
DISPLAY 0.638298 (-2850 -1600);
FORCEPROP 1 LAST PACK_TYPE C0402
J 0
(-2850 -1850);
DISPLAY 0.638298 (-2850 -1850);
FORCEPROP 1 LAST MATERIAL X6S
J 0
(-2850 -1750);
DISPLAY 0.638298 (-2850 -1750);
FORCEPROP 1 LAST VOLTAGE 4V
J 0
(-2850 -1650);
DISPLAY 0.638298 (-2850 -1650);
FORCEPROP 1 LAST TOLERANCE 20%
J 0
(-2850 -1700);
DISPLAY 0.638298 (-2850 -1700);
FORCEPROP 1 LAST $LOCATION C406
J 0
(-2850 -1550);
DISPLAY 0.978723 (-2850 -1550);
FORCEPROP 1 LASTPIN (-2900 -1550) $PN 1
J 0
(-2890 -1570);
DISPLAY 0.787234 (-2890 -1570);
FORCEPROP 1 LASTPIN (-2900 -1750) $PN 2
J 0
(-2890 -1770);
DISPLAY 0.787234 (-2890 -1770);
FORCEPROP 2 LAST CDS_LIB pure_quanta
J 0
(-2900 -1650);
PAINT MONO (-2900 -1650);
DISPLAY INVISIBLE (-2900 -1650);
FORCEPROP 2 LAST CDS_LOCATION C406
J 0
(-2850 -1450);
DISPLAY 1.021277 (-2850 -1450);
DISPLAY INVISIBLE (-2850 -1450);
FORCEPROP 2 LAST $SEC 1
J 0
(-2850 -1450);
DISPLAY 0.680851 (-2850 -1450);
PAINT MONO (-2850 -1450);
DISPLAY INVISIBLE (-2850 -1450);
FORCEPROP 2 LAST CDS_SEC 1
J 0
(-2850 -1450);
DISPLAY 1.021277 (-2850 -1450);
DISPLAY INVISIBLE (-2850 -1450);
FORCEPROP 1 LAST PATH I5
J 0
(-2850 -1500);
DISPLAY 0.978723 (-2850 -1500);
PAINT WHITE (-2850 -1500);
DISPLAY INVISIBLE (-2850 -1500);
FORCEADD Q_CAP..1
(-2925 2250);
FORCEPROP 1 LAST PART_NUMBER CH6101MEB03
J 0
(-2875 2100);
DISPLAY 0.638298 (-2875 2100);
DISPLAY INVISIBLE (-2875 2100);
FORCEPROP 1 LAST PACK_TYPE C0402
J 0
(-2875 2050);
DISPLAY 0.638298 (-2875 2050);
FORCEPROP 1 LAST MATERIAL X6S
J 0
(-2875 2150);
DISPLAY 0.638298 (-2875 2150);
FORCEPROP 1 LAST TOLERANCE 20%
J 0
(-2875 2200);
DISPLAY 0.638298 (-2875 2200);
FORCEPROP 1 LAST VALUE 10UF
J 0
(-2875 2300);
DISPLAY 0.638298 (-2875 2300);
FORCEPROP 1 LAST VOLTAGE 6.3V
J 0
(-2875 2250);
DISPLAY 0.638298 (-2875 2250);
FORCEPROP 1 LAST $LOCATION C979
J 0
(-2875 2350);
DISPLAY 0.638298 (-2875 2350);
FORCEPROP 1 LASTPIN (-2925 2350) $PN 1
J 0
(-2915 2330);
DISPLAY 0.787234 (-2915 2330);
FORCEPROP 1 LASTPIN (-2925 2150) $PN 2
J 0
(-2915 2130);
DISPLAY 0.787234 (-2915 2130);
FORCEPROP 2 LAST CDS_LIB pure_quanta
J 0
(-2925 2250);
PAINT MONO (-2925 2250);
DISPLAY INVISIBLE (-2925 2250);
FORCEPROP 2 LAST CDS_LOCATION C979
J 0
(-2875 2450);
DISPLAY 1.021277 (-2875 2450);
DISPLAY INVISIBLE (-2875 2450);
FORCEPROP 2 LAST $SEC 1
J 0
(-2875 2450);
DISPLAY 0.680851 (-2875 2450);
PAINT MONO (-2875 2450);
DISPLAY INVISIBLE (-2875 2450);
FORCEPROP 2 LAST CDS_SEC 1
J 0
(-2875 2450);
DISPLAY 1.021277 (-2875 2450);
DISPLAY INVISIBLE (-2875 2450);
FORCEPROP 1 LAST PATH I50
J 0
(-2875 2400);
DISPLAY 0.978723 (-2875 2400);
PAINT WHITE (-2875 2400);
DISPLAY INVISIBLE (-2875 2400);
FORCEADD Q_CAP..1
(-2925 3025);
FORCEPROP 1 LAST PART_NUMBER CH6101MEB03
J 0
(-2875 2875);
DISPLAY 0.638298 (-2875 2875);
DISPLAY INVISIBLE (-2875 2875);
FORCEPROP 1 LAST PACK_TYPE C0402
J 0
(-2875 2825);
DISPLAY 0.638298 (-2875 2825);
FORCEPROP 1 LAST TOLERANCE 20%
J 0
(-2875 2975);
DISPLAY 0.638298 (-2875 2975);
FORCEPROP 1 LAST MATERIAL X6S
J 0
(-2875 2925);
DISPLAY 0.638298 (-2875 2925);
FORCEPROP 1 LAST VALUE 10UF
J 0
(-2875 3075);
DISPLAY 0.638298 (-2875 3075);
FORCEPROP 1 LAST VOLTAGE 6.3V
J 0
(-2875 3025);
DISPLAY 0.638298 (-2875 3025);
FORCEPROP 1 LAST $LOCATION C978
J 0
(-2875 3125);
DISPLAY 0.638298 (-2875 3125);
FORCEPROP 1 LASTPIN (-2925 3125) $PN 1
J 0
(-2915 3105);
DISPLAY 0.787234 (-2915 3105);
FORCEPROP 1 LASTPIN (-2925 2925) $PN 2
J 0
(-2915 2905);
DISPLAY 0.787234 (-2915 2905);
FORCEPROP 2 LAST CDS_LIB pure_quanta
J 0
(-2925 3025);
PAINT MONO (-2925 3025);
DISPLAY INVISIBLE (-2925 3025);
FORCEPROP 2 LAST CDS_LOCATION C978
J 0
(-2875 3225);
DISPLAY 1.021277 (-2875 3225);
DISPLAY INVISIBLE (-2875 3225);
FORCEPROP 2 LAST $SEC 1
J 0
(-2875 3225);
DISPLAY 0.680851 (-2875 3225);
PAINT MONO (-2875 3225);
DISPLAY INVISIBLE (-2875 3225);
FORCEPROP 2 LAST CDS_SEC 1
J 0
(-2875 3225);
DISPLAY 1.021277 (-2875 3225);
DISPLAY INVISIBLE (-2875 3225);
FORCEPROP 1 LAST PATH I51
J 0
(-2875 3175);
DISPLAY 0.978723 (-2875 3175);
PAINT WHITE (-2875 3175);
DISPLAY INVISIBLE (-2875 3175);
FORCEADD Q_CAP..1
(-2475 2250);
FORCEPROP 1 LAST PART_NUMBER CH6101MEB03
J 0
(-2425 2100);
DISPLAY 0.638298 (-2425 2100);
DISPLAY INVISIBLE (-2425 2100);
FORCEPROP 1 LAST PACK_TYPE C0402
J 0
(-2425 2050);
DISPLAY 0.638298 (-2425 2050);
FORCEPROP 1 LAST MATERIAL X6S
J 0
(-2425 2150);
DISPLAY 0.638298 (-2425 2150);
FORCEPROP 1 LAST TOLERANCE 20%
J 0
(-2425 2200);
DISPLAY 0.638298 (-2425 2200);
FORCEPROP 1 LAST VALUE 10UF
J 0
(-2425 2300);
DISPLAY 0.638298 (-2425 2300);
FORCEPROP 1 LAST VOLTAGE 6.3V
J 0
(-2425 2250);
DISPLAY 0.638298 (-2425 2250);
FORCEPROP 1 LAST $LOCATION C983
J 0
(-2425 2350);
DISPLAY 0.638298 (-2425 2350);
FORCEPROP 1 LASTPIN (-2475 2350) $PN 1
J 0
(-2465 2330);
DISPLAY 0.787234 (-2465 2330);
FORCEPROP 1 LASTPIN (-2475 2150) $PN 2
J 0
(-2465 2130);
DISPLAY 0.787234 (-2465 2130);
FORCEPROP 2 LAST CDS_LIB pure_quanta
J 0
(-2475 2250);
PAINT MONO (-2475 2250);
DISPLAY INVISIBLE (-2475 2250);
FORCEPROP 2 LAST CDS_LOCATION C983
J 0
(-2425 2450);
DISPLAY 1.021277 (-2425 2450);
DISPLAY INVISIBLE (-2425 2450);
FORCEPROP 2 LAST $SEC 1
J 0
(-2425 2450);
DISPLAY 0.680851 (-2425 2450);
PAINT MONO (-2425 2450);
DISPLAY INVISIBLE (-2425 2450);
FORCEPROP 2 LAST CDS_SEC 1
J 0
(-2425 2450);
DISPLAY 1.021277 (-2425 2450);
DISPLAY INVISIBLE (-2425 2450);
FORCEPROP 1 LAST PATH I52
J 0
(-2425 2400);
DISPLAY 0.978723 (-2425 2400);
PAINT WHITE (-2425 2400);
DISPLAY INVISIBLE (-2425 2400);
FORCEADD Q_CAP..1
(-2475 3025);
FORCEPROP 1 LAST PART_NUMBER CH6101MEB03
J 0
(-2425 2875);
DISPLAY 0.638298 (-2425 2875);
DISPLAY INVISIBLE (-2425 2875);
FORCEPROP 1 LAST PACK_TYPE C0402
J 0
(-2425 2825);
DISPLAY 0.638298 (-2425 2825);
FORCEPROP 1 LAST TOLERANCE 20%
J 0
(-2425 2975);
DISPLAY 0.638298 (-2425 2975);
FORCEPROP 1 LAST MATERIAL X6S
J 0
(-2425 2925);
DISPLAY 0.638298 (-2425 2925);
FORCEPROP 1 LAST VALUE 10UF
J 0
(-2425 3075);
DISPLAY 0.638298 (-2425 3075);
FORCEPROP 1 LAST VOLTAGE 6.3V
J 0
(-2425 3025);
DISPLAY 0.638298 (-2425 3025);
FORCEPROP 1 LAST $LOCATION C982
J 0
(-2425 3125);
DISPLAY 0.638298 (-2425 3125);
FORCEPROP 1 LASTPIN (-2475 3125) $PN 1
J 0
(-2465 3105);
DISPLAY 0.787234 (-2465 3105);
FORCEPROP 1 LASTPIN (-2475 2925) $PN 2
J 0
(-2465 2905);
DISPLAY 0.787234 (-2465 2905);
FORCEPROP 2 LAST CDS_LIB pure_quanta
J 0
(-2475 3025);
PAINT MONO (-2475 3025);
DISPLAY INVISIBLE (-2475 3025);
FORCEPROP 2 LAST CDS_LOCATION C982
J 0
(-2425 3225);
DISPLAY 1.021277 (-2425 3225);
DISPLAY INVISIBLE (-2425 3225);
FORCEPROP 2 LAST $SEC 1
J 0
(-2425 3225);
DISPLAY 0.680851 (-2425 3225);
PAINT MONO (-2425 3225);
DISPLAY INVISIBLE (-2425 3225);
FORCEPROP 2 LAST CDS_SEC 1
J 0
(-2425 3225);
DISPLAY 1.021277 (-2425 3225);
DISPLAY INVISIBLE (-2425 3225);
FORCEPROP 1 LAST PATH I53
J 0
(-2425 3175);
DISPLAY 0.978723 (-2425 3175);
PAINT WHITE (-2425 3175);
DISPLAY INVISIBLE (-2425 3175);
FORCEADD Q_CAP..1
(-2000 1500);
FORCEPROP 1 LAST PART_NUMBER CH6101MEB03
J 0
(-1950 1350);
DISPLAY 0.638298 (-1950 1350);
DISPLAY INVISIBLE (-1950 1350);
FORCEPROP 1 LAST PACK_TYPE C0402
J 0
(-1950 1300);
DISPLAY 0.638298 (-1950 1300);
FORCEPROP 1 LAST TOLERANCE 20%
J 0
(-1950 1450);
DISPLAY 0.638298 (-1950 1450);
FORCEPROP 1 LAST VALUE 10UF
J 0
(-1950 1550);
DISPLAY 0.638298 (-1950 1550);
FORCEPROP 1 LAST VOLTAGE 6.3V
J 0
(-1950 1500);
DISPLAY 0.638298 (-1950 1500);
FORCEPROP 1 LAST MATERIAL X6S
J 0
(-1950 1400);
DISPLAY 0.638298 (-1950 1400);
FORCEPROP 1 LAST $LOCATION C988
J 0
(-1950 1600);
DISPLAY 0.638298 (-1950 1600);
FORCEPROP 1 LASTPIN (-2000 1600) $PN 1
J 0
(-1990 1580);
DISPLAY 0.787234 (-1990 1580);
FORCEPROP 1 LASTPIN (-2000 1400) $PN 2
J 0
(-1990 1380);
DISPLAY 0.787234 (-1990 1380);
FORCEPROP 2 LAST CDS_LIB pure_quanta
J 0
(-2000 1500);
PAINT MONO (-2000 1500);
DISPLAY INVISIBLE (-2000 1500);
FORCEPROP 2 LAST CDS_LOCATION C988
J 0
(-1950 1700);
DISPLAY 1.021277 (-1950 1700);
DISPLAY INVISIBLE (-1950 1700);
FORCEPROP 2 LAST $SEC 1
J 0
(-1950 1700);
DISPLAY 0.680851 (-1950 1700);
PAINT MONO (-1950 1700);
DISPLAY INVISIBLE (-1950 1700);
FORCEPROP 2 LAST CDS_SEC 1
J 0
(-1950 1700);
DISPLAY 1.021277 (-1950 1700);
DISPLAY INVISIBLE (-1950 1700);
FORCEPROP 1 LAST PATH I54
J 0
(-1950 1650);
DISPLAY 0.978723 (-1950 1650);
PAINT WHITE (-1950 1650);
DISPLAY INVISIBLE (-1950 1650);
FORCEADD Q_CAP..1
(-1550 1500);
FORCEPROP 1 LAST PART_NUMBER CH6101MEB03
J 0
(-1500 1350);
DISPLAY 0.638298 (-1500 1350);
DISPLAY INVISIBLE (-1500 1350);
FORCEPROP 1 LAST VALUE 10UF
J 0
(-1500 1550);
DISPLAY 0.638298 (-1500 1550);
FORCEPROP 1 LAST PACK_TYPE C0402
J 0
(-1500 1300);
DISPLAY 0.638298 (-1500 1300);
FORCEPROP 1 LAST MATERIAL X6S
J 0
(-1500 1400);
DISPLAY 0.638298 (-1500 1400);
FORCEPROP 1 LAST TOLERANCE 20%
J 0
(-1500 1450);
DISPLAY 0.638298 (-1500 1450);
FORCEPROP 1 LAST VOLTAGE 6.3V
J 0
(-1500 1500);
DISPLAY 0.638298 (-1500 1500);
FORCEPROP 1 LAST $LOCATION C992
J 0
(-1500 1600);
DISPLAY 0.638298 (-1500 1600);
FORCEPROP 1 LASTPIN (-1550 1600) $PN 1
J 0
(-1540 1580);
DISPLAY 0.787234 (-1540 1580);
FORCEPROP 1 LASTPIN (-1550 1400) $PN 2
J 0
(-1540 1380);
DISPLAY 0.787234 (-1540 1380);
FORCEPROP 2 LAST CDS_LIB pure_quanta
J 0
(-1550 1500);
PAINT MONO (-1550 1500);
DISPLAY INVISIBLE (-1550 1500);
FORCEPROP 2 LAST CDS_LOCATION C992
J 0
(-1500 1700);
DISPLAY 1.021277 (-1500 1700);
DISPLAY INVISIBLE (-1500 1700);
FORCEPROP 2 LAST $SEC 1
J 0
(-1500 1700);
DISPLAY 0.680851 (-1500 1700);
PAINT MONO (-1500 1700);
DISPLAY INVISIBLE (-1500 1700);
FORCEPROP 2 LAST CDS_SEC 1
J 0
(-1500 1700);
DISPLAY 1.021277 (-1500 1700);
DISPLAY INVISIBLE (-1500 1700);
FORCEPROP 1 LAST PATH I55
J 0
(-1500 1650);
DISPLAY 0.978723 (-1500 1650);
PAINT WHITE (-1500 1650);
DISPLAY INVISIBLE (-1500 1650);
FORCEADD Q_CAP..1
(-1100 1500);
FORCEPROP 1 LAST PART_NUMBER CH6101MEB03
J 0
(-1050 1350);
DISPLAY 0.638298 (-1050 1350);
DISPLAY INVISIBLE (-1050 1350);
FORCEPROP 1 LAST PACK_TYPE C0402
J 0
(-1050 1300);
DISPLAY 0.638298 (-1050 1300);
FORCEPROP 1 LAST TOLERANCE 20%
J 0
(-1050 1450);
DISPLAY 0.638298 (-1050 1450);
FORCEPROP 1 LAST VALUE 10UF
J 0
(-1050 1550);
DISPLAY 0.638298 (-1050 1550);
FORCEPROP 1 LAST MATERIAL X6S
J 0
(-1050 1400);
DISPLAY 0.638298 (-1050 1400);
FORCEPROP 1 LAST VOLTAGE 6.3V
J 0
(-1050 1500);
DISPLAY 0.638298 (-1050 1500);
FORCEPROP 1 LAST $LOCATION C996
J 0
(-1050 1600);
DISPLAY 0.638298 (-1050 1600);
FORCEPROP 1 LASTPIN (-1100 1600) $PN 1
J 0
(-1090 1580);
DISPLAY 0.787234 (-1090 1580);
FORCEPROP 1 LASTPIN (-1100 1400) $PN 2
J 0
(-1090 1380);
DISPLAY 0.787234 (-1090 1380);
FORCEPROP 2 LAST CDS_LIB pure_quanta
J 0
(-1100 1500);
PAINT MONO (-1100 1500);
DISPLAY INVISIBLE (-1100 1500);
FORCEPROP 2 LAST CDS_LOCATION C996
J 0
(-1050 1700);
DISPLAY 1.021277 (-1050 1700);
DISPLAY INVISIBLE (-1050 1700);
FORCEPROP 2 LAST $SEC 1
J 0
(-1050 1700);
DISPLAY 0.680851 (-1050 1700);
PAINT MONO (-1050 1700);
DISPLAY INVISIBLE (-1050 1700);
FORCEPROP 2 LAST CDS_SEC 1
J 0
(-1050 1700);
DISPLAY 1.021277 (-1050 1700);
DISPLAY INVISIBLE (-1050 1700);
FORCEPROP 1 LAST PATH I56
J 0
(-1050 1650);
DISPLAY 0.978723 (-1050 1650);
PAINT WHITE (-1050 1650);
DISPLAY INVISIBLE (-1050 1650);
FORCEADD Q_CAP..1
(-2025 2250);
FORCEPROP 1 LAST PART_NUMBER CH6101MEB03
J 0
(-1975 2100);
DISPLAY 0.638298 (-1975 2100);
DISPLAY INVISIBLE (-1975 2100);
FORCEPROP 1 LAST MATERIAL X6S
J 0
(-1975 2150);
DISPLAY 0.638298 (-1975 2150);
FORCEPROP 1 LAST PACK_TYPE C0402
J 0
(-1975 2050);
DISPLAY 0.638298 (-1975 2050);
FORCEPROP 1 LAST TOLERANCE 20%
J 0
(-1975 2200);
DISPLAY 0.638298 (-1975 2200);
FORCEPROP 1 LAST VALUE 10UF
J 0
(-1975 2300);
DISPLAY 0.638298 (-1975 2300);
FORCEPROP 1 LAST VOLTAGE 6.3V
J 0
(-1975 2250);
DISPLAY 0.638298 (-1975 2250);
FORCEPROP 1 LAST $LOCATION C987
J 0
(-1975 2350);
DISPLAY 0.638298 (-1975 2350);
FORCEPROP 1 LASTPIN (-2025 2350) $PN 1
J 0
(-2015 2330);
DISPLAY 0.787234 (-2015 2330);
FORCEPROP 1 LASTPIN (-2025 2150) $PN 2
J 0
(-2015 2130);
DISPLAY 0.787234 (-2015 2130);
FORCEPROP 2 LAST CDS_LIB pure_quanta
J 0
(-2025 2250);
PAINT MONO (-2025 2250);
DISPLAY INVISIBLE (-2025 2250);
FORCEPROP 2 LAST CDS_LOCATION C987
J 0
(-1975 2450);
DISPLAY 1.021277 (-1975 2450);
DISPLAY INVISIBLE (-1975 2450);
FORCEPROP 2 LAST $SEC 1
J 0
(-1975 2450);
DISPLAY 0.680851 (-1975 2450);
PAINT MONO (-1975 2450);
DISPLAY INVISIBLE (-1975 2450);
FORCEPROP 2 LAST CDS_SEC 1
J 0
(-1975 2450);
DISPLAY 1.021277 (-1975 2450);
DISPLAY INVISIBLE (-1975 2450);
FORCEPROP 1 LAST PATH I57
J 0
(-1975 2400);
DISPLAY 0.978723 (-1975 2400);
PAINT WHITE (-1975 2400);
DISPLAY INVISIBLE (-1975 2400);
FORCEADD Q_CAP..1
(-2025 3025);
FORCEPROP 1 LAST PART_NUMBER CH6101MEB03
J 0
(-1975 2875);
DISPLAY 0.638298 (-1975 2875);
DISPLAY INVISIBLE (-1975 2875);
FORCEPROP 1 LAST PACK_TYPE C0402
J 0
(-1975 2825);
DISPLAY 0.638298 (-1975 2825);
FORCEPROP 1 LAST TOLERANCE 20%
J 0
(-1975 2975);
DISPLAY 0.638298 (-1975 2975);
FORCEPROP 1 LAST MATERIAL X6S
J 0
(-1975 2925);
DISPLAY 0.638298 (-1975 2925);
FORCEPROP 1 LAST VALUE 10UF
J 0
(-1975 3075);
DISPLAY 0.638298 (-1975 3075);
FORCEPROP 1 LAST VOLTAGE 6.3V
J 0
(-1975 3025);
DISPLAY 0.638298 (-1975 3025);
FORCEPROP 1 LAST $LOCATION C986
J 0
(-1975 3125);
DISPLAY 0.638298 (-1975 3125);
FORCEPROP 1 LASTPIN (-2025 3125) $PN 1
J 0
(-2015 3105);
DISPLAY 0.787234 (-2015 3105);
FORCEPROP 1 LASTPIN (-2025 2925) $PN 2
J 0
(-2015 2905);
DISPLAY 0.787234 (-2015 2905);
FORCEPROP 2 LAST CDS_LIB pure_quanta
J 0
(-2025 3025);
PAINT MONO (-2025 3025);
DISPLAY INVISIBLE (-2025 3025);
FORCEPROP 2 LAST CDS_LOCATION C986
J 0
(-1975 3225);
DISPLAY 1.021277 (-1975 3225);
DISPLAY INVISIBLE (-1975 3225);
FORCEPROP 2 LAST $SEC 1
J 0
(-1975 3225);
DISPLAY 0.680851 (-1975 3225);
PAINT MONO (-1975 3225);
DISPLAY INVISIBLE (-1975 3225);
FORCEPROP 2 LAST CDS_SEC 1
J 0
(-1975 3225);
DISPLAY 1.021277 (-1975 3225);
DISPLAY INVISIBLE (-1975 3225);
FORCEPROP 1 LAST PATH I58
J 0
(-1975 3175);
DISPLAY 0.978723 (-1975 3175);
PAINT WHITE (-1975 3175);
DISPLAY INVISIBLE (-1975 3175);
FORCEADD Q_CAP..1
(-1575 2250);
FORCEPROP 1 LAST PART_NUMBER CH6101MEB03
J 0
(-1525 2100);
DISPLAY 0.638298 (-1525 2100);
DISPLAY INVISIBLE (-1525 2100);
FORCEPROP 1 LAST PACK_TYPE C0402
J 0
(-1525 2050);
DISPLAY 0.638298 (-1525 2050);
FORCEPROP 1 LAST VALUE 10UF
J 0
(-1525 2300);
DISPLAY 0.638298 (-1525 2300);
FORCEPROP 1 LAST VOLTAGE 6.3V
J 0
(-1525 2250);
DISPLAY 0.638298 (-1525 2250);
FORCEPROP 1 LAST TOLERANCE 20%
J 0
(-1525 2200);
DISPLAY 0.638298 (-1525 2200);
FORCEPROP 1 LAST MATERIAL X6S
J 0
(-1525 2150);
DISPLAY 0.638298 (-1525 2150);
FORCEPROP 1 LAST $LOCATION C991
J 0
(-1525 2350);
DISPLAY 0.638298 (-1525 2350);
FORCEPROP 1 LASTPIN (-1575 2350) $PN 1
J 0
(-1565 2330);
DISPLAY 0.787234 (-1565 2330);
FORCEPROP 1 LASTPIN (-1575 2150) $PN 2
J 0
(-1565 2130);
DISPLAY 0.787234 (-1565 2130);
FORCEPROP 2 LAST CDS_LIB pure_quanta
J 0
(-1575 2250);
PAINT MONO (-1575 2250);
DISPLAY INVISIBLE (-1575 2250);
FORCEPROP 2 LAST CDS_LOCATION C991
J 0
(-1525 2450);
DISPLAY 1.021277 (-1525 2450);
DISPLAY INVISIBLE (-1525 2450);
FORCEPROP 2 LAST $SEC 1
J 0
(-1525 2450);
DISPLAY 0.680851 (-1525 2450);
PAINT MONO (-1525 2450);
DISPLAY INVISIBLE (-1525 2450);
FORCEPROP 2 LAST CDS_SEC 1
J 0
(-1525 2450);
DISPLAY 1.021277 (-1525 2450);
DISPLAY INVISIBLE (-1525 2450);
FORCEPROP 1 LAST PATH I59
J 0
(-1525 2400);
DISPLAY 0.978723 (-1525 2400);
PAINT WHITE (-1525 2400);
DISPLAY INVISIBLE (-1525 2400);
FORCEADD UNIVERSAL_GND..1
(-2900 -1175);
FORCEPROP 3 LASTPIN (-2900 -1125) SIG_NAME GND\g
J 0
(-2890 -1115);
DISPLAY 0.659574 (-2890 -1115);
PAINT MONO (-2890 -1115);
DISPLAY INVISIBLE (-2890 -1115);
FORCEPROP 2 LAST CDS_LIB logical_power
J 0
(-2900 -1175);
PAINT MONO (-2900 -1175);
DISPLAY INVISIBLE (-2900 -1175);
FORCEPROP 1 LAST HDL_POWER GND
J 1
(-2875 -1250);
DISPLAY 0.872340 (-2875 -1250);
PAINT GREEN (-2875 -1250);
DISPLAY INVISIBLE (-2875 -1250);
FORCEPROP 1 LAST PATH I6
J 0
(-2825 -1175);
DISPLAY 0.872340 (-2825 -1175);
PAINT AQUA (-2825 -1175);
DISPLAY INVISIBLE (-2825 -1175);
FORCEADD Q_CAP..1
(-1575 3025);
FORCEPROP 1 LAST PART_NUMBER CH6101MEB03
J 0
(-1525 2875);
DISPLAY 0.638298 (-1525 2875);
DISPLAY INVISIBLE (-1525 2875);
FORCEPROP 1 LAST PACK_TYPE C0402
J 0
(-1525 2825);
DISPLAY 0.638298 (-1525 2825);
FORCEPROP 1 LAST TOLERANCE 20%
J 0
(-1525 2975);
DISPLAY 0.638298 (-1525 2975);
FORCEPROP 1 LAST MATERIAL X6S
J 0
(-1525 2925);
DISPLAY 0.638298 (-1525 2925);
FORCEPROP 1 LAST VALUE 10UF
J 0
(-1525 3075);
DISPLAY 0.638298 (-1525 3075);
FORCEPROP 1 LAST VOLTAGE 6.3V
J 0
(-1525 3025);
DISPLAY 0.638298 (-1525 3025);
FORCEPROP 1 LAST $LOCATION C990
J 0
(-1525 3125);
DISPLAY 0.638298 (-1525 3125);
FORCEPROP 1 LASTPIN (-1575 3125) $PN 1
J 0
(-1565 3105);
DISPLAY 0.787234 (-1565 3105);
FORCEPROP 1 LASTPIN (-1575 2925) $PN 2
J 0
(-1565 2905);
DISPLAY 0.787234 (-1565 2905);
FORCEPROP 2 LAST CDS_LIB pure_quanta
J 0
(-1575 3025);
PAINT MONO (-1575 3025);
DISPLAY INVISIBLE (-1575 3025);
FORCEPROP 2 LAST CDS_LOCATION C990
J 0
(-1525 3225);
DISPLAY 1.021277 (-1525 3225);
DISPLAY INVISIBLE (-1525 3225);
FORCEPROP 2 LAST $SEC 1
J 0
(-1525 3225);
DISPLAY 0.680851 (-1525 3225);
PAINT MONO (-1525 3225);
DISPLAY INVISIBLE (-1525 3225);
FORCEPROP 2 LAST CDS_SEC 1
J 0
(-1525 3225);
DISPLAY 1.021277 (-1525 3225);
DISPLAY INVISIBLE (-1525 3225);
FORCEPROP 1 LAST PATH I60
J 0
(-1525 3175);
DISPLAY 0.978723 (-1525 3175);
PAINT WHITE (-1525 3175);
DISPLAY INVISIBLE (-1525 3175);
FORCEADD Q_CAP..1
(-1125 2250);
FORCEPROP 1 LAST PART_NUMBER CH6101MEB03
J 0
(-1075 2100);
DISPLAY 0.638298 (-1075 2100);
DISPLAY INVISIBLE (-1075 2100);
FORCEPROP 1 LAST MATERIAL X6S
J 0
(-1075 2150);
DISPLAY 0.638298 (-1075 2150);
FORCEPROP 1 LAST PACK_TYPE C0402
J 0
(-1075 2050);
DISPLAY 0.638298 (-1075 2050);
FORCEPROP 1 LAST TOLERANCE 20%
J 0
(-1075 2200);
DISPLAY 0.638298 (-1075 2200);
FORCEPROP 1 LAST VALUE 10UF
J 0
(-1075 2300);
DISPLAY 0.638298 (-1075 2300);
FORCEPROP 1 LAST VOLTAGE 6.3V
J 0
(-1075 2250);
DISPLAY 0.638298 (-1075 2250);
FORCEPROP 1 LAST $LOCATION C995
J 0
(-1075 2350);
DISPLAY 0.638298 (-1075 2350);
FORCEPROP 1 LASTPIN (-1125 2350) $PN 1
J 0
(-1115 2330);
DISPLAY 0.787234 (-1115 2330);
FORCEPROP 1 LASTPIN (-1125 2150) $PN 2
J 0
(-1115 2130);
DISPLAY 0.787234 (-1115 2130);
FORCEPROP 2 LAST CDS_LIB pure_quanta
J 0
(-1125 2250);
PAINT MONO (-1125 2250);
DISPLAY INVISIBLE (-1125 2250);
FORCEPROP 2 LAST CDS_LOCATION C995
J 0
(-1075 2450);
DISPLAY 1.021277 (-1075 2450);
DISPLAY INVISIBLE (-1075 2450);
FORCEPROP 2 LAST $SEC 1
J 0
(-1075 2450);
DISPLAY 0.680851 (-1075 2450);
PAINT MONO (-1075 2450);
DISPLAY INVISIBLE (-1075 2450);
FORCEPROP 2 LAST CDS_SEC 1
J 0
(-1075 2450);
DISPLAY 1.021277 (-1075 2450);
DISPLAY INVISIBLE (-1075 2450);
FORCEPROP 1 LAST PATH I61
J 0
(-1075 2400);
DISPLAY 0.978723 (-1075 2400);
PAINT WHITE (-1075 2400);
DISPLAY INVISIBLE (-1075 2400);
FORCEADD Q_CAP..1
(-1125 3025);
FORCEPROP 1 LAST PART_NUMBER CH6101MEB03
J 0
(-1075 2875);
DISPLAY 0.638298 (-1075 2875);
DISPLAY INVISIBLE (-1075 2875);
FORCEPROP 1 LAST PACK_TYPE C0402
J 0
(-1075 2825);
DISPLAY 0.638298 (-1075 2825);
FORCEPROP 1 LAST TOLERANCE 20%
J 0
(-1075 2975);
DISPLAY 0.638298 (-1075 2975);
FORCEPROP 1 LAST MATERIAL X6S
J 0
(-1075 2925);
DISPLAY 0.638298 (-1075 2925);
FORCEPROP 1 LAST VALUE 10UF
J 0
(-1075 3075);
DISPLAY 0.638298 (-1075 3075);
FORCEPROP 1 LAST VOLTAGE 6.3V
J 0
(-1075 3025);
DISPLAY 0.638298 (-1075 3025);
FORCEPROP 1 LAST $LOCATION C994
J 0
(-1075 3125);
DISPLAY 0.638298 (-1075 3125);
FORCEPROP 1 LASTPIN (-1125 3125) $PN 1
J 0
(-1115 3105);
DISPLAY 0.787234 (-1115 3105);
FORCEPROP 1 LASTPIN (-1125 2925) $PN 2
J 0
(-1115 2905);
DISPLAY 0.787234 (-1115 2905);
FORCEPROP 2 LAST CDS_LIB pure_quanta
J 0
(-1125 3025);
PAINT MONO (-1125 3025);
DISPLAY INVISIBLE (-1125 3025);
FORCEPROP 2 LAST CDS_LOCATION C994
J 0
(-1075 3225);
DISPLAY 1.021277 (-1075 3225);
DISPLAY INVISIBLE (-1075 3225);
FORCEPROP 2 LAST $SEC 1
J 0
(-1075 3225);
DISPLAY 0.680851 (-1075 3225);
PAINT MONO (-1075 3225);
DISPLAY INVISIBLE (-1075 3225);
FORCEPROP 2 LAST CDS_SEC 1
J 0
(-1075 3225);
DISPLAY 1.021277 (-1075 3225);
DISPLAY INVISIBLE (-1075 3225);
FORCEPROP 1 LAST PATH I62
J 0
(-1075 3175);
DISPLAY 0.978723 (-1075 3175);
PAINT WHITE (-1075 3175);
DISPLAY INVISIBLE (-1075 3175);
FORCEADD UNIVERSAL_POWER..1
(-4275 3300);
FORCEPROP 3 LASTPIN (-4275 3250) SIG_NAME PVCCIN_CPU0\g
J 0
(-4265 3260);
DISPLAY 0.659574 (-4265 3260);
PAINT MONO (-4265 3260);
DISPLAY INVISIBLE (-4265 3260);
FORCEPROP 1 LAST HDL_POWER PVCCIN_CPU0
J 1
(-4075 3350);
DISPLAY 0.872340 (-4075 3350);
PAINT GREEN (-4075 3350);
FORCEPROP 2 LAST CDS_LIB logical_power
J 0
(-4275 3300);
DISPLAY INVISIBLE (-4275 3300);
FORCEPROP 1 LAST PATH I63
J 0
(-4225 3325);
DISPLAY 0.872340 (-4225 3325);
PAINT AQUA (-4225 3325);
DISPLAY INVISIBLE (-4225 3325);
FORCEADD Q_CAP..1
(-650 -1650);
FORCEPROP 1 LAST PART_NUMBER CH622KMEB01
J 0
(-600 -1800);
DISPLAY 0.638298 (-600 -1800);
DISPLAY INVISIBLE (-600 -1800);
FORCEPROP 1 LAST VALUE 22UF
J 0
(-600 -1600);
DISPLAY 0.638298 (-600 -1600);
FORCEPROP 1 LAST PACK_TYPE C0402
J 0
(-600 -1850);
DISPLAY 0.638298 (-600 -1850);
FORCEPROP 1 LAST MATERIAL X6S
J 0
(-600 -1750);
DISPLAY 0.638298 (-600 -1750);
FORCEPROP 1 LAST VOLTAGE 4V
J 0
(-600 -1650);
DISPLAY 0.638298 (-600 -1650);
FORCEPROP 1 LAST TOLERANCE 20%
J 0
(-600 -1700);
DISPLAY 0.638298 (-600 -1700);
FORCEPROP 1 LAST $LOCATION C415
J 0
(-600 -1550);
DISPLAY 0.978723 (-600 -1550);
FORCEPROP 1 LASTPIN (-650 -1550) $PN 1
J 0
(-640 -1570);
DISPLAY 0.787234 (-640 -1570);
FORCEPROP 1 LASTPIN (-650 -1750) $PN 2
J 0
(-640 -1770);
DISPLAY 0.787234 (-640 -1770);
FORCEPROP 2 LAST CDS_LIB pure_quanta
J 0
(-650 -1650);
PAINT MONO (-650 -1650);
DISPLAY INVISIBLE (-650 -1650);
FORCEPROP 2 LAST CDS_LOCATION C415
J 0
(-600 -1450);
DISPLAY 1.021277 (-600 -1450);
DISPLAY INVISIBLE (-600 -1450);
FORCEPROP 2 LAST $SEC 1
J 0
(-600 -1450);
DISPLAY 0.680851 (-600 -1450);
PAINT MONO (-600 -1450);
DISPLAY INVISIBLE (-600 -1450);
FORCEPROP 2 LAST CDS_SEC 1
J 0
(-600 -1450);
DISPLAY 1.021277 (-600 -1450);
DISPLAY INVISIBLE (-600 -1450);
FORCEPROP 1 LAST PATH I64
J 0
(-600 -1500);
DISPLAY 0.978723 (-600 -1500);
PAINT WHITE (-600 -1500);
DISPLAY INVISIBLE (-600 -1500);
FORCEADD Q_CAP..1
(-200 -1650);
FORCEPROP 1 LAST PART_NUMBER CH622KMEB01
J 0
(-150 -1800);
DISPLAY 0.638298 (-150 -1800);
DISPLAY INVISIBLE (-150 -1800);
FORCEPROP 1 LAST VALUE 22UF
J 0
(-150 -1600);
DISPLAY 0.638298 (-150 -1600);
FORCEPROP 1 LAST PACK_TYPE C0402
J 0
(-150 -1850);
DISPLAY 0.638298 (-150 -1850);
FORCEPROP 1 LAST MATERIAL X6S
J 0
(-150 -1750);
DISPLAY 0.638298 (-150 -1750);
FORCEPROP 1 LAST VOLTAGE 4V
J 0
(-150 -1650);
DISPLAY 0.638298 (-150 -1650);
FORCEPROP 1 LAST TOLERANCE 20%
J 0
(-150 -1700);
DISPLAY 0.638298 (-150 -1700);
FORCEPROP 1 LAST $LOCATION C417
J 0
(-150 -1550);
DISPLAY 0.978723 (-150 -1550);
FORCEPROP 1 LASTPIN (-200 -1550) $PN 1
J 0
(-190 -1570);
DISPLAY 0.787234 (-190 -1570);
FORCEPROP 1 LASTPIN (-200 -1750) $PN 2
J 0
(-190 -1770);
DISPLAY 0.787234 (-190 -1770);
FORCEPROP 2 LAST CDS_LIB pure_quanta
J 0
(-200 -1650);
PAINT MONO (-200 -1650);
DISPLAY INVISIBLE (-200 -1650);
FORCEPROP 2 LAST CDS_LOCATION C417
J 0
(-150 -1450);
DISPLAY 1.021277 (-150 -1450);
DISPLAY INVISIBLE (-150 -1450);
FORCEPROP 2 LAST $SEC 1
J 0
(-150 -1450);
DISPLAY 0.680851 (-150 -1450);
PAINT MONO (-150 -1450);
DISPLAY INVISIBLE (-150 -1450);
FORCEPROP 2 LAST CDS_SEC 1
J 0
(-150 -1450);
DISPLAY 1.021277 (-150 -1450);
DISPLAY INVISIBLE (-150 -1450);
FORCEPROP 1 LAST PATH I65
J 0
(-150 -1500);
DISPLAY 0.978723 (-150 -1500);
PAINT WHITE (-150 -1500);
DISPLAY INVISIBLE (-150 -1500);
FORCEADD UNIVERSAL_GND..1
(-200 -1200);
FORCEPROP 3 LASTPIN (-200 -1150) SIG_NAME GND\g
J 0
(-190 -1140);
DISPLAY 0.659574 (-190 -1140);
PAINT MONO (-190 -1140);
DISPLAY INVISIBLE (-190 -1140);
FORCEPROP 2 LAST CDS_LIB logical_power
J 0
(-200 -1200);
PAINT MONO (-200 -1200);
DISPLAY INVISIBLE (-200 -1200);
FORCEPROP 1 LAST HDL_POWER GND
J 1
(-175 -1275);
DISPLAY 0.872340 (-175 -1275);
PAINT GREEN (-175 -1275);
DISPLAY INVISIBLE (-175 -1275);
FORCEPROP 1 LAST PATH I66
J 0
(-125 -1200);
DISPLAY 0.872340 (-125 -1200);
PAINT AQUA (-125 -1200);
DISPLAY INVISIBLE (-125 -1200);
FORCEADD UNIVERSAL_GND..1
(250 -2000);
FORCEPROP 3 LASTPIN (250 -1950) SIG_NAME GND\g
J 0
(260 -1940);
DISPLAY 0.659574 (260 -1940);
PAINT MONO (260 -1940);
DISPLAY INVISIBLE (260 -1940);
FORCEPROP 2 LAST CDS_LIB logical_power
J 0
(250 -2000);
PAINT MONO (250 -2000);
DISPLAY INVISIBLE (250 -2000);
FORCEPROP 1 LAST HDL_POWER GND
J 1
(275 -2075);
DISPLAY 0.872340 (275 -2075);
PAINT GREEN (275 -2075);
DISPLAY INVISIBLE (275 -2075);
FORCEPROP 1 LAST PATH I67
J 0
(325 -2000);
DISPLAY 0.872340 (325 -2000);
PAINT AQUA (325 -2000);
DISPLAY INVISIBLE (325 -2000);
FORCEADD Q_CAP..1
(250 -1650);
FORCEPROP 1 LAST PART_NUMBER CH622KMEB01
J 0
(300 -1800);
DISPLAY 0.638298 (300 -1800);
DISPLAY INVISIBLE (300 -1800);
FORCEPROP 1 LAST MATERIAL X6S
J 0
(300 -1750);
DISPLAY 0.638298 (300 -1750);
FORCEPROP 1 LAST PACK_TYPE C0402
J 0
(300 -1850);
DISPLAY 0.638298 (300 -1850);
FORCEPROP 1 LAST VALUE 22UF
J 0
(300 -1600);
DISPLAY 0.638298 (300 -1600);
FORCEPROP 1 LAST TOLERANCE 20%
J 0
(300 -1700);
DISPLAY 0.638298 (300 -1700);
FORCEPROP 1 LAST VOLTAGE 4V
J 0
(300 -1650);
DISPLAY 0.638298 (300 -1650);
FORCEPROP 1 LAST $LOCATION C418
J 0
(300 -1550);
DISPLAY 0.978723 (300 -1550);
FORCEPROP 1 LASTPIN (250 -1550) $PN 1
J 0
(260 -1570);
DISPLAY 0.787234 (260 -1570);
FORCEPROP 1 LASTPIN (250 -1750) $PN 2
J 0
(260 -1770);
DISPLAY 0.787234 (260 -1770);
FORCEPROP 2 LAST CDS_LIB pure_quanta
J 0
(250 -1650);
PAINT MONO (250 -1650);
DISPLAY INVISIBLE (250 -1650);
FORCEPROP 2 LAST CDS_LOCATION C418
J 0
(300 -1450);
DISPLAY 1.021277 (300 -1450);
DISPLAY INVISIBLE (300 -1450);
FORCEPROP 2 LAST $SEC 1
J 0
(300 -1450);
DISPLAY 0.680851 (300 -1450);
PAINT MONO (300 -1450);
DISPLAY INVISIBLE (300 -1450);
FORCEPROP 2 LAST CDS_SEC 1
J 0
(300 -1450);
DISPLAY 1.021277 (300 -1450);
DISPLAY INVISIBLE (300 -1450);
FORCEPROP 1 LAST PATH I68
J 0
(300 -1500);
DISPLAY 0.978723 (300 -1500);
PAINT WHITE (300 -1500);
DISPLAY INVISIBLE (300 -1500);
FORCEADD UNIVERSAL_GND..1
(2375 -1175);
FORCEPROP 3 LASTPIN (2375 -1125) SIG_NAME GND\g
J 0
(2385 -1115);
DISPLAY 0.659574 (2385 -1115);
PAINT MONO (2385 -1115);
DISPLAY INVISIBLE (2385 -1115);
FORCEPROP 2 LAST CDS_LIB logical_power
J 0
(2375 -1175);
PAINT MONO (2375 -1175);
DISPLAY INVISIBLE (2375 -1175);
FORCEPROP 1 LAST HDL_POWER GND
J 1
(2400 -1250);
DISPLAY 0.872340 (2400 -1250);
PAINT GREEN (2400 -1250);
DISPLAY INVISIBLE (2400 -1250);
FORCEPROP 1 LAST PATH I69
J 0
(2450 -1175);
DISPLAY 0.872340 (2450 -1175);
PAINT AQUA (2450 -1175);
DISPLAY INVISIBLE (2450 -1175);
FORCEADD Q_CAP..1
(-2450 -1650);
FORCEPROP 1 LAST PART_NUMBER CH622KMEB01
J 0
(-2400 -1800);
DISPLAY 0.638298 (-2400 -1800);
DISPLAY INVISIBLE (-2400 -1800);
FORCEPROP 1 LAST PACK_TYPE C0402
J 0
(-2400 -1850);
DISPLAY 0.638298 (-2400 -1850);
FORCEPROP 1 LAST VALUE 22UF
J 0
(-2400 -1600);
DISPLAY 0.638298 (-2400 -1600);
FORCEPROP 1 LAST MATERIAL X6S
J 0
(-2400 -1750);
DISPLAY 0.638298 (-2400 -1750);
FORCEPROP 1 LAST VOLTAGE 4V
J 0
(-2400 -1650);
DISPLAY 0.638298 (-2400 -1650);
FORCEPROP 1 LAST TOLERANCE 20%
J 0
(-2400 -1700);
DISPLAY 0.638298 (-2400 -1700);
FORCEPROP 1 LAST $LOCATION C407
J 0
(-2400 -1550);
DISPLAY 0.978723 (-2400 -1550);
FORCEPROP 1 LASTPIN (-2450 -1550) $PN 1
J 0
(-2440 -1570);
DISPLAY 0.787234 (-2440 -1570);
FORCEPROP 1 LASTPIN (-2450 -1750) $PN 2
J 0
(-2440 -1770);
DISPLAY 0.787234 (-2440 -1770);
FORCEPROP 2 LAST CDS_LIB pure_quanta
J 0
(-2450 -1650);
PAINT MONO (-2450 -1650);
DISPLAY INVISIBLE (-2450 -1650);
FORCEPROP 2 LAST CDS_LOCATION C407
J 0
(-2400 -1450);
DISPLAY 1.021277 (-2400 -1450);
DISPLAY INVISIBLE (-2400 -1450);
FORCEPROP 2 LAST $SEC 1
J 0
(-2400 -1450);
DISPLAY 0.680851 (-2400 -1450);
PAINT MONO (-2400 -1450);
DISPLAY INVISIBLE (-2400 -1450);
FORCEPROP 2 LAST CDS_SEC 1
J 0
(-2400 -1450);
DISPLAY 1.021277 (-2400 -1450);
DISPLAY INVISIBLE (-2400 -1450);
FORCEPROP 1 LAST PATH I7
J 0
(-2400 -1500);
DISPLAY 0.978723 (-2400 -1500);
PAINT WHITE (-2400 -1500);
DISPLAY INVISIBLE (-2400 -1500);
FORCEADD Q_CAP..1
(-650 -850);
FORCEPROP 1 LAST PART_NUMBER CH622KMEB01
J 0
(-600 -1000);
DISPLAY 0.638298 (-600 -1000);
DISPLAY INVISIBLE (-600 -1000);
FORCEPROP 1 LAST PACK_TYPE C0402
J 0
(-600 -1050);
DISPLAY 0.638298 (-600 -1050);
FORCEPROP 1 LAST MATERIAL X6S
J 0
(-600 -950);
DISPLAY 0.638298 (-600 -950);
FORCEPROP 1 LAST VALUE 22UF
J 0
(-600 -800);
DISPLAY 0.638298 (-600 -800);
FORCEPROP 1 LAST VOLTAGE 4V
J 0
(-600 -850);
DISPLAY 0.638298 (-600 -850);
FORCEPROP 1 LAST TOLERANCE 20%
J 0
(-600 -900);
DISPLAY 0.638298 (-600 -900);
FORCEPROP 1 LAST $LOCATION C414
J 0
(-600 -750);
DISPLAY 0.978723 (-600 -750);
FORCEPROP 1 LASTPIN (-650 -750) $PN 1
J 0
(-640 -770);
DISPLAY 0.787234 (-640 -770);
FORCEPROP 1 LASTPIN (-650 -950) $PN 2
J 0
(-640 -970);
DISPLAY 0.787234 (-640 -970);
FORCEPROP 2 LAST CDS_LIB pure_quanta
J 0
(-650 -850);
PAINT MONO (-650 -850);
DISPLAY INVISIBLE (-650 -850);
FORCEPROP 2 LAST CDS_LOCATION C414
J 0
(-600 -650);
DISPLAY 1.021277 (-600 -650);
DISPLAY INVISIBLE (-600 -650);
FORCEPROP 2 LAST $SEC 1
J 0
(-600 -650);
DISPLAY 0.680851 (-600 -650);
PAINT MONO (-600 -650);
DISPLAY INVISIBLE (-600 -650);
FORCEPROP 2 LAST CDS_SEC 1
J 0
(-600 -650);
DISPLAY 1.021277 (-600 -650);
DISPLAY INVISIBLE (-600 -650);
FORCEPROP 1 LAST PATH I70
J 0
(-600 -700);
DISPLAY 0.978723 (-600 -700);
PAINT WHITE (-600 -700);
DISPLAY INVISIBLE (-600 -700);
FORCEADD Q_CAP..1
(-650 -50);
FORCEPROP 1 LAST PART_NUMBER CH647KMEA04
J 0
(-600 -200);
DISPLAY 0.638298 (-600 -200);
DISPLAY INVISIBLE (-600 -200);
FORCEPROP 1 LAST MATERIAL X6S
J 0
(-600 -150);
DISPLAY 0.638298 (-600 -150);
FORCEPROP 1 LAST PACK_TYPE C0805
J 0
(-600 -250);
DISPLAY 0.638298 (-600 -250);
FORCEPROP 1 LAST VOLTAGE 4V
J 0
(-600 -50);
DISPLAY 0.638298 (-600 -50);
FORCEPROP 1 LAST TOLERANCE 20%
J 0
(-600 -100);
DISPLAY 0.638298 (-600 -100);
FORCEPROP 1 LAST VALUE 47UF
J 0
(-600 0);
DISPLAY 0.638298 (-600 0);
FORCEPROP 1 LAST $LOCATION C219
J 0
(-600 50);
DISPLAY 0.638298 (-600 50);
FORCEPROP 1 LASTPIN (-650 50) $PN 1
J 0
(-640 30);
DISPLAY 0.787234 (-640 30);
FORCEPROP 1 LASTPIN (-650 -150) $PN 2
J 0
(-640 -170);
DISPLAY 0.787234 (-640 -170);
FORCEPROP 2 LAST CDS_LIB pure_quanta
J 0
(-650 -50);
PAINT MONO (-650 -50);
DISPLAY INVISIBLE (-650 -50);
FORCEPROP 1 LAST $LOCATION C219
J 0
(-600 150);
DISPLAY 1.021277 (-600 150);
DISPLAY INVISIBLE (-600 150);
FORCEPROP 2 LAST CDS_LOCATION C219
J 0
(-600 150);
DISPLAY 1.021277 (-600 150);
DISPLAY INVISIBLE (-600 150);
FORCEPROP 2 LAST $SEC 1
J 0
(-600 150);
DISPLAY 0.680851 (-600 150);
PAINT MONO (-600 150);
DISPLAY INVISIBLE (-600 150);
FORCEPROP 2 LAST CDS_SEC 1
J 0
(-600 150);
DISPLAY 1.021277 (-600 150);
DISPLAY INVISIBLE (-600 150);
FORCEPROP 1 LAST PATH I71
J 0
(-600 100);
DISPLAY 0.978723 (-600 100);
PAINT WHITE (-600 100);
DISPLAY INVISIBLE (-600 100);
FORCEADD Q_CAP..1
(-200 -850);
FORCEPROP 1 LAST PART_NUMBER CH622KMEB01
J 0
(-150 -1000);
DISPLAY 0.638298 (-150 -1000);
DISPLAY INVISIBLE (-150 -1000);
FORCEPROP 1 LAST MATERIAL X6S
J 0
(-150 -950);
DISPLAY 0.638298 (-150 -950);
FORCEPROP 1 LAST VOLTAGE 4V
J 0
(-150 -850);
DISPLAY 0.638298 (-150 -850);
FORCEPROP 1 LAST TOLERANCE 20%
J 0
(-150 -900);
DISPLAY 0.638298 (-150 -900);
FORCEPROP 1 LAST VALUE 22UF
J 0
(-150 -800);
DISPLAY 0.638298 (-150 -800);
FORCEPROP 1 LAST PACK_TYPE C0402
J 0
(-150 -1050);
DISPLAY 0.638298 (-150 -1050);
FORCEPROP 1 LAST $LOCATION C416
J 0
(-150 -750);
DISPLAY 0.978723 (-150 -750);
FORCEPROP 1 LASTPIN (-200 -750) $PN 1
J 0
(-190 -770);
DISPLAY 0.787234 (-190 -770);
FORCEPROP 1 LASTPIN (-200 -950) $PN 2
J 0
(-190 -970);
DISPLAY 0.787234 (-190 -970);
FORCEPROP 2 LAST CDS_LIB pure_quanta
J 0
(-200 -850);
PAINT MONO (-200 -850);
DISPLAY INVISIBLE (-200 -850);
FORCEPROP 2 LAST CDS_LOCATION C416
J 0
(-150 -650);
DISPLAY 1.021277 (-150 -650);
DISPLAY INVISIBLE (-150 -650);
FORCEPROP 2 LAST $SEC 1
J 0
(-150 -650);
DISPLAY 0.680851 (-150 -650);
PAINT MONO (-150 -650);
DISPLAY INVISIBLE (-150 -650);
FORCEPROP 2 LAST CDS_SEC 1
J 0
(-150 -650);
DISPLAY 1.021277 (-150 -650);
DISPLAY INVISIBLE (-150 -650);
FORCEPROP 1 LAST PATH I72
J 0
(-150 -700);
DISPLAY 0.978723 (-150 -700);
PAINT WHITE (-150 -700);
DISPLAY INVISIBLE (-150 -700);
FORCEADD UNIVERSAL_GND..1
(-200 -400);
FORCEPROP 3 LASTPIN (-200 -350) SIG_NAME GND\g
J 0
(-190 -340);
DISPLAY 0.659574 (-190 -340);
PAINT MONO (-190 -340);
DISPLAY INVISIBLE (-190 -340);
FORCEPROP 2 LAST CDS_LIB logical_power
J 0
(-200 -400);
PAINT MONO (-200 -400);
DISPLAY INVISIBLE (-200 -400);
FORCEPROP 1 LAST HDL_POWER GND
J 1
(-175 -475);
DISPLAY 0.872340 (-175 -475);
PAINT GREEN (-175 -475);
DISPLAY INVISIBLE (-175 -475);
FORCEPROP 1 LAST PATH I73
J 0
(-125 -400);
DISPLAY 0.872340 (-125 -400);
PAINT AQUA (-125 -400);
DISPLAY INVISIBLE (-125 -400);
FORCEADD Q_CAP..1
(-200 -50);
FORCEPROP 1 LAST PART_NUMBER CH647KMEA04
J 0
(-150 -200);
DISPLAY 0.638298 (-150 -200);
DISPLAY INVISIBLE (-150 -200);
FORCEPROP 1 LAST MATERIAL X6S
J 0
(-150 -150);
DISPLAY 0.638298 (-150 -150);
FORCEPROP 1 LAST PACK_TYPE C0805
J 0
(-150 -250);
DISPLAY 0.638298 (-150 -250);
FORCEPROP 1 LAST VOLTAGE 4V
J 0
(-150 -50);
DISPLAY 0.638298 (-150 -50);
FORCEPROP 1 LAST TOLERANCE 20%
J 0
(-150 -100);
DISPLAY 0.638298 (-150 -100);
FORCEPROP 1 LAST VALUE 47UF
J 0
(-150 0);
DISPLAY 0.638298 (-150 0);
FORCEPROP 1 LAST $LOCATION C220
J 0
(-150 50);
DISPLAY 0.638298 (-150 50);
FORCEPROP 1 LASTPIN (-200 50) $PN 1
J 0
(-190 30);
DISPLAY 0.787234 (-190 30);
FORCEPROP 1 LASTPIN (-200 -150) $PN 2
J 0
(-190 -170);
DISPLAY 0.787234 (-190 -170);
FORCEPROP 2 LAST CDS_LIB pure_quanta
J 0
(-200 -50);
PAINT MONO (-200 -50);
DISPLAY INVISIBLE (-200 -50);
FORCEPROP 1 LAST $LOCATION C220
J 0
(-150 150);
DISPLAY 1.021277 (-150 150);
DISPLAY INVISIBLE (-150 150);
FORCEPROP 2 LAST CDS_LOCATION C220
J 0
(-150 150);
DISPLAY 1.021277 (-150 150);
DISPLAY INVISIBLE (-150 150);
FORCEPROP 2 LAST $SEC 1
J 0
(-150 150);
DISPLAY 0.680851 (-150 150);
PAINT MONO (-150 150);
DISPLAY INVISIBLE (-150 150);
FORCEPROP 2 LAST CDS_SEC 1
J 0
(-150 150);
DISPLAY 1.021277 (-150 150);
DISPLAY INVISIBLE (-150 150);
FORCEPROP 1 LAST PATH I74
J 0
(-150 100);
DISPLAY 0.978723 (-150 100);
PAINT WHITE (-150 100);
DISPLAY INVISIBLE (-150 100);
FORCEADD Q_CAP..1
(-650 725);
FORCEPROP 1 LAST PART_NUMBER CH6101MEB03
J 0
(-600 575);
DISPLAY 0.638298 (-600 575);
DISPLAY INVISIBLE (-600 575);
FORCEPROP 1 LAST VOLTAGE 6.3V
J 0
(-600 725);
DISPLAY 0.638298 (-600 725);
FORCEPROP 1 LAST VALUE 10UF
J 0
(-600 775);
DISPLAY 0.638298 (-600 775);
FORCEPROP 1 LAST PACK_TYPE C0402
J 0
(-600 525);
DISPLAY 0.638298 (-600 525);
FORCEPROP 1 LAST MATERIAL X6S
J 0
(-600 625);
DISPLAY 0.638298 (-600 625);
FORCEPROP 1 LAST TOLERANCE 20%
J 0
(-600 675);
DISPLAY 0.638298 (-600 675);
FORCEPROP 1 LAST $LOCATION C1001
J 0
(-600 825);
DISPLAY 0.638298 (-600 825);
FORCEPROP 1 LASTPIN (-650 825) $PN 1
J 0
(-640 805);
DISPLAY 0.787234 (-640 805);
FORCEPROP 1 LASTPIN (-650 625) $PN 2
J 0
(-640 605);
DISPLAY 0.787234 (-640 605);
FORCEPROP 2 LAST CDS_LIB pure_quanta
J 0
(-650 725);
PAINT MONO (-650 725);
DISPLAY INVISIBLE (-650 725);
FORCEPROP 2 LAST CDS_LOCATION C1001
J 0
(-600 925);
DISPLAY 1.021277 (-600 925);
DISPLAY INVISIBLE (-600 925);
FORCEPROP 2 LAST $SEC 1
J 0
(-600 925);
DISPLAY 0.680851 (-600 925);
PAINT MONO (-600 925);
DISPLAY INVISIBLE (-600 925);
FORCEPROP 2 LAST CDS_SEC 1
J 0
(-600 925);
DISPLAY 1.021277 (-600 925);
DISPLAY INVISIBLE (-600 925);
FORCEPROP 1 LAST PATH I75
J 0
(-600 875);
DISPLAY 0.978723 (-600 875);
PAINT WHITE (-600 875);
DISPLAY INVISIBLE (-600 875);
FORCEADD UNIVERSAL_GND..1
(-200 375);
FORCEPROP 3 LASTPIN (-200 425) SIG_NAME GND\g
J 0
(-190 435);
DISPLAY 0.659574 (-190 435);
PAINT MONO (-190 435);
DISPLAY INVISIBLE (-190 435);
FORCEPROP 2 LAST CDS_LIB logical_power
J 0
(-200 375);
PAINT MONO (-200 375);
DISPLAY INVISIBLE (-200 375);
FORCEPROP 1 LAST HDL_POWER GND
J 1
(-175 300);
DISPLAY 0.872340 (-175 300);
PAINT GREEN (-175 300);
DISPLAY INVISIBLE (-175 300);
FORCEPROP 1 LAST PATH I76
J 0
(-125 375);
DISPLAY 0.872340 (-125 375);
PAINT AQUA (-125 375);
DISPLAY INVISIBLE (-125 375);
FORCEADD Q_CAP..1
(-200 725);
FORCEPROP 1 LAST PART_NUMBER CH6101MEB03
J 0
(-150 575);
DISPLAY 0.638298 (-150 575);
DISPLAY INVISIBLE (-150 575);
FORCEPROP 1 LAST VOLTAGE 6.3V
J 0
(-150 725);
DISPLAY 0.638298 (-150 725);
FORCEPROP 1 LAST VALUE 10UF
J 0
(-150 775);
DISPLAY 0.638298 (-150 775);
FORCEPROP 1 LAST PACK_TYPE C0402
J 0
(-150 525);
DISPLAY 0.638298 (-150 525);
FORCEPROP 1 LAST MATERIAL X6S
J 0
(-150 625);
DISPLAY 0.638298 (-150 625);
FORCEPROP 1 LAST TOLERANCE 20%
J 0
(-150 675);
DISPLAY 0.638298 (-150 675);
FORCEPROP 1 LAST $LOCATION C1005
J 0
(-150 825);
DISPLAY 0.638298 (-150 825);
FORCEPROP 1 LASTPIN (-200 825) $PN 1
J 0
(-190 805);
DISPLAY 0.787234 (-190 805);
FORCEPROP 1 LASTPIN (-200 625) $PN 2
J 0
(-190 605);
DISPLAY 0.787234 (-190 605);
FORCEPROP 2 LAST CDS_LIB pure_quanta
J 0
(-200 725);
PAINT MONO (-200 725);
DISPLAY INVISIBLE (-200 725);
FORCEPROP 2 LAST CDS_LOCATION C1005
J 0
(-150 925);
DISPLAY 1.021277 (-150 925);
DISPLAY INVISIBLE (-150 925);
FORCEPROP 2 LAST $SEC 1
J 0
(-150 925);
DISPLAY 0.680851 (-150 925);
PAINT MONO (-150 925);
DISPLAY INVISIBLE (-150 925);
FORCEPROP 2 LAST CDS_SEC 1
J 0
(-150 925);
DISPLAY 1.021277 (-150 925);
DISPLAY INVISIBLE (-150 925);
FORCEPROP 1 LAST PATH I77
J 0
(-150 875);
DISPLAY 0.978723 (-150 875);
PAINT WHITE (-150 875);
DISPLAY INVISIBLE (-150 875);
FORCEADD Q_CAP..1
(275 725);
FORCEPROP 1 LAST PART_NUMBER CH622KMEB01
J 0
(325 575);
DISPLAY 0.638298 (325 575);
DISPLAY INVISIBLE (325 575);
FORCEPROP 1 LAST PACK_TYPE C0402
J 0
(325 525);
DISPLAY 0.638298 (325 525);
FORCEPROP 1 LAST MATERIAL X6S
J 0
(325 625);
DISPLAY 0.638298 (325 625);
FORCEPROP 1 LAST TOLERANCE 20%
J 0
(325 675);
DISPLAY 0.638298 (325 675);
FORCEPROP 1 LAST VOLTAGE 4V
J 0
(325 725);
DISPLAY 0.638298 (325 725);
FORCEPROP 1 LAST VALUE 22UF
J 0
(325 775);
DISPLAY 0.638298 (325 775);
FORCEPROP 1 LAST $LOCATION C1009
J 0
(325 825);
DISPLAY 0.638298 (325 825);
FORCEPROP 1 LASTPIN (275 825) $PN 1
J 0
(285 805);
DISPLAY 0.787234 (285 805);
FORCEPROP 1 LASTPIN (275 625) $PN 2
J 0
(285 605);
DISPLAY 0.787234 (285 605);
FORCEPROP 2 LAST CDS_LIB pure_quanta
J 0
(275 725);
PAINT MONO (275 725);
DISPLAY INVISIBLE (275 725);
FORCEPROP 2 LAST CDS_LOCATION C1009
J 0
(325 925);
DISPLAY 1.021277 (325 925);
DISPLAY INVISIBLE (325 925);
FORCEPROP 2 LAST $SEC 1
J 0
(325 925);
DISPLAY 0.680851 (325 925);
PAINT MONO (325 925);
DISPLAY INVISIBLE (325 925);
FORCEPROP 2 LAST CDS_SEC 1
J 0
(325 925);
DISPLAY 1.021277 (325 925);
DISPLAY INVISIBLE (325 925);
FORCEPROP 1 LAST PATH I78
J 0
(325 875);
DISPLAY 0.978723 (325 875);
PAINT WHITE (325 875);
DISPLAY INVISIBLE (325 875);
FORCEADD UNIVERSAL_POWER..1
(275 1000);
FORCEPROP 3 LASTPIN (275 950) SIG_NAME PVCCIN_CPU0\g
J 0
(285 960);
DISPLAY 0.659574 (285 960);
PAINT MONO (285 960);
DISPLAY INVISIBLE (285 960);
FORCEPROP 1 LAST HDL_POWER PVCCIN_CPU0
J 1
(475 1050);
DISPLAY 0.872340 (475 1050);
PAINT GREEN (475 1050);
FORCEPROP 2 LAST CDS_LIB logical_power
J 0
(275 1000);
DISPLAY INVISIBLE (275 1000);
FORCEPROP 1 LAST PATH I79
J 0
(325 1025);
DISPLAY 0.872340 (325 1025);
PAINT AQUA (325 1025);
DISPLAY INVISIBLE (325 1025);
FORCEADD Q_CAP..1
(-2000 -1650);
FORCEPROP 1 LAST PART_NUMBER CH622KMEB01
J 0
(-1950 -1800);
DISPLAY 0.638298 (-1950 -1800);
DISPLAY INVISIBLE (-1950 -1800);
FORCEPROP 1 LAST PACK_TYPE C0402
J 0
(-1950 -1850);
DISPLAY 0.638298 (-1950 -1850);
FORCEPROP 1 LAST MATERIAL X6S
J 0
(-1950 -1750);
DISPLAY 0.638298 (-1950 -1750);
FORCEPROP 1 LAST VOLTAGE 4V
J 0
(-1950 -1650);
DISPLAY 0.638298 (-1950 -1650);
FORCEPROP 1 LAST TOLERANCE 20%
J 0
(-1950 -1700);
DISPLAY 0.638298 (-1950 -1700);
FORCEPROP 1 LAST VALUE 22UF
J 0
(-1950 -1600);
DISPLAY 0.638298 (-1950 -1600);
FORCEPROP 1 LAST $LOCATION C409
J 0
(-1950 -1550);
DISPLAY 0.978723 (-1950 -1550);
FORCEPROP 1 LASTPIN (-2000 -1550) $PN 1
J 0
(-1990 -1570);
DISPLAY 0.787234 (-1990 -1570);
FORCEPROP 1 LASTPIN (-2000 -1750) $PN 2
J 0
(-1990 -1770);
DISPLAY 0.787234 (-1990 -1770);
FORCEPROP 2 LAST CDS_LIB pure_quanta
J 0
(-2000 -1650);
PAINT MONO (-2000 -1650);
DISPLAY INVISIBLE (-2000 -1650);
FORCEPROP 2 LAST CDS_LOCATION C409
J 0
(-1950 -1450);
DISPLAY 1.021277 (-1950 -1450);
DISPLAY INVISIBLE (-1950 -1450);
FORCEPROP 2 LAST $SEC 1
J 0
(-1950 -1450);
DISPLAY 0.680851 (-1950 -1450);
PAINT MONO (-1950 -1450);
DISPLAY INVISIBLE (-1950 -1450);
FORCEPROP 2 LAST CDS_SEC 1
J 0
(-1950 -1450);
DISPLAY 1.021277 (-1950 -1450);
DISPLAY INVISIBLE (-1950 -1450);
FORCEPROP 1 LAST PATH I8
J 0
(-1950 -1500);
DISPLAY 0.978723 (-1950 -1500);
PAINT WHITE (-1950 -1500);
DISPLAY INVISIBLE (-1950 -1500);
FORCEADD Q_CAP..1
(725 725);
FORCEPROP 1 LAST PART_NUMBER CH622KMEB01
J 0
(775 575);
DISPLAY 0.638298 (775 575);
DISPLAY INVISIBLE (775 575);
FORCEPROP 1 LAST PACK_TYPE C0402
J 0
(775 525);
DISPLAY 0.638298 (775 525);
FORCEPROP 1 LAST VALUE 22UF
J 0
(775 775);
DISPLAY 0.638298 (775 775);
FORCEPROP 1 LAST VOLTAGE 4V
J 0
(775 725);
DISPLAY 0.638298 (775 725);
FORCEPROP 1 LAST MATERIAL X6S
J 0
(775 625);
DISPLAY 0.638298 (775 625);
FORCEPROP 1 LAST TOLERANCE 20%
J 0
(775 675);
DISPLAY 0.638298 (775 675);
FORCEPROP 1 LAST $LOCATION C1013
J 0
(775 825);
DISPLAY 0.638298 (775 825);
FORCEPROP 1 LASTPIN (725 825) $PN 1
J 0
(735 805);
DISPLAY 0.787234 (735 805);
FORCEPROP 1 LASTPIN (725 625) $PN 2
J 0
(735 605);
DISPLAY 0.787234 (735 605);
FORCEPROP 2 LAST CDS_LIB pure_quanta
J 0
(725 725);
PAINT MONO (725 725);
DISPLAY INVISIBLE (725 725);
FORCEPROP 2 LAST CDS_LOCATION C1013
J 0
(775 925);
DISPLAY 1.021277 (775 925);
DISPLAY INVISIBLE (775 925);
FORCEPROP 2 LAST $SEC 1
J 0
(775 925);
DISPLAY 0.680851 (775 925);
PAINT MONO (775 925);
DISPLAY INVISIBLE (775 925);
FORCEPROP 2 LAST CDS_SEC 1
J 0
(775 925);
DISPLAY 1.021277 (775 925);
DISPLAY INVISIBLE (775 925);
FORCEPROP 1 LAST PATH I80
J 0
(775 875);
DISPLAY 0.978723 (775 875);
PAINT WHITE (775 875);
DISPLAY INVISIBLE (775 875);
FORCEADD Q_CAP..1
(-650 1500);
FORCEPROP 1 LAST PART_NUMBER CH6101MEB03
J 0
(-600 1350);
DISPLAY 0.638298 (-600 1350);
DISPLAY INVISIBLE (-600 1350);
FORCEPROP 1 LAST VOLTAGE 6.3V
J 0
(-600 1500);
DISPLAY 0.638298 (-600 1500);
FORCEPROP 1 LAST MATERIAL X6S
J 0
(-600 1400);
DISPLAY 0.638298 (-600 1400);
FORCEPROP 1 LAST PACK_TYPE C0402
J 0
(-600 1300);
DISPLAY 0.638298 (-600 1300);
FORCEPROP 1 LAST TOLERANCE 20%
J 0
(-600 1450);
DISPLAY 0.638298 (-600 1450);
FORCEPROP 1 LAST VALUE 10UF
J 0
(-600 1550);
DISPLAY 0.638298 (-600 1550);
FORCEPROP 1 LAST $LOCATION C1000
J 0
(-600 1600);
DISPLAY 0.638298 (-600 1600);
FORCEPROP 1 LASTPIN (-650 1600) $PN 1
J 0
(-640 1580);
DISPLAY 0.787234 (-640 1580);
FORCEPROP 1 LASTPIN (-650 1400) $PN 2
J 0
(-640 1380);
DISPLAY 0.787234 (-640 1380);
FORCEPROP 2 LAST CDS_LIB pure_quanta
J 0
(-650 1500);
PAINT MONO (-650 1500);
DISPLAY INVISIBLE (-650 1500);
FORCEPROP 2 LAST CDS_LOCATION C1000
J 0
(-600 1700);
DISPLAY 1.021277 (-600 1700);
DISPLAY INVISIBLE (-600 1700);
FORCEPROP 2 LAST $SEC 1
J 0
(-600 1700);
DISPLAY 0.680851 (-600 1700);
PAINT MONO (-600 1700);
DISPLAY INVISIBLE (-600 1700);
FORCEPROP 2 LAST CDS_SEC 1
J 0
(-600 1700);
DISPLAY 1.021277 (-600 1700);
DISPLAY INVISIBLE (-600 1700);
FORCEPROP 1 LAST PATH I81
J 0
(-600 1650);
DISPLAY 0.978723 (-600 1650);
PAINT WHITE (-600 1650);
DISPLAY INVISIBLE (-600 1650);
FORCEADD UNIVERSAL_GND..1
(-200 1150);
FORCEPROP 3 LASTPIN (-200 1200) SIG_NAME GND\g
J 0
(-190 1210);
DISPLAY 0.659574 (-190 1210);
PAINT MONO (-190 1210);
DISPLAY INVISIBLE (-190 1210);
FORCEPROP 2 LAST CDS_LIB logical_power
J 0
(-200 1150);
PAINT MONO (-200 1150);
DISPLAY INVISIBLE (-200 1150);
FORCEPROP 1 LAST HDL_POWER GND
J 1
(-175 1075);
DISPLAY 0.872340 (-175 1075);
PAINT GREEN (-175 1075);
DISPLAY INVISIBLE (-175 1075);
FORCEPROP 1 LAST PATH I82
J 0
(-125 1150);
DISPLAY 0.872340 (-125 1150);
PAINT AQUA (-125 1150);
DISPLAY INVISIBLE (-125 1150);
FORCEADD Q_CAP..1
(-200 1500);
FORCEPROP 1 LAST PART_NUMBER CH6101MEB03
J 0
(-150 1350);
DISPLAY 0.638298 (-150 1350);
DISPLAY INVISIBLE (-150 1350);
FORCEPROP 1 LAST PACK_TYPE C0402
J 0
(-150 1300);
DISPLAY 0.638298 (-150 1300);
FORCEPROP 1 LAST VALUE 10UF
J 0
(-150 1550);
DISPLAY 0.638298 (-150 1550);
FORCEPROP 1 LAST MATERIAL X6S
J 0
(-150 1400);
DISPLAY 0.638298 (-150 1400);
FORCEPROP 1 LAST TOLERANCE 20%
J 0
(-150 1450);
DISPLAY 0.638298 (-150 1450);
FORCEPROP 1 LAST VOLTAGE 6.3V
J 0
(-150 1500);
DISPLAY 0.638298 (-150 1500);
FORCEPROP 1 LAST $LOCATION C1004
J 0
(-150 1600);
DISPLAY 0.638298 (-150 1600);
FORCEPROP 1 LASTPIN (-200 1600) $PN 1
J 0
(-190 1580);
DISPLAY 0.787234 (-190 1580);
FORCEPROP 1 LASTPIN (-200 1400) $PN 2
J 0
(-190 1380);
DISPLAY 0.787234 (-190 1380);
FORCEPROP 2 LAST CDS_LIB pure_quanta
J 0
(-200 1500);
PAINT MONO (-200 1500);
DISPLAY INVISIBLE (-200 1500);
FORCEPROP 2 LAST CDS_LOCATION C1004
J 0
(-150 1700);
DISPLAY 1.021277 (-150 1700);
DISPLAY INVISIBLE (-150 1700);
FORCEPROP 2 LAST $SEC 1
J 0
(-150 1700);
DISPLAY 0.680851 (-150 1700);
PAINT MONO (-150 1700);
DISPLAY INVISIBLE (-150 1700);
FORCEPROP 2 LAST CDS_SEC 1
J 0
(-150 1700);
DISPLAY 1.021277 (-150 1700);
DISPLAY INVISIBLE (-150 1700);
FORCEPROP 1 LAST PATH I83
J 0
(-150 1650);
DISPLAY 0.978723 (-150 1650);
PAINT WHITE (-150 1650);
DISPLAY INVISIBLE (-150 1650);
FORCEADD UNIVERSAL_GND..1
(-225 1900);
FORCEPROP 3 LASTPIN (-225 1950) SIG_NAME GND\g
J 0
(-215 1960);
DISPLAY 0.659574 (-215 1960);
PAINT MONO (-215 1960);
DISPLAY INVISIBLE (-215 1960);
FORCEPROP 2 LAST CDS_LIB logical_power
J 0
(-225 1900);
PAINT MONO (-225 1900);
DISPLAY INVISIBLE (-225 1900);
FORCEPROP 1 LAST HDL_POWER GND
J 1
(-200 1825);
DISPLAY 0.872340 (-200 1825);
PAINT GREEN (-200 1825);
DISPLAY INVISIBLE (-200 1825);
FORCEPROP 1 LAST PATH I84
J 0
(-150 1900);
DISPLAY 0.872340 (-150 1900);
PAINT AQUA (-150 1900);
DISPLAY INVISIBLE (-150 1900);
FORCEADD Q_CAP..1
(-675 2250);
FORCEPROP 1 LAST PART_NUMBER CH6101MEB03
J 0
(-625 2100);
DISPLAY 0.638298 (-625 2100);
DISPLAY INVISIBLE (-625 2100);
FORCEPROP 1 LAST MATERIAL X6S
J 0
(-625 2150);
DISPLAY 0.638298 (-625 2150);
FORCEPROP 1 LAST PACK_TYPE C0402
J 0
(-625 2050);
DISPLAY 0.638298 (-625 2050);
FORCEPROP 1 LAST TOLERANCE 20%
J 0
(-625 2200);
DISPLAY 0.638298 (-625 2200);
FORCEPROP 1 LAST VALUE 10UF
J 0
(-625 2300);
DISPLAY 0.638298 (-625 2300);
FORCEPROP 1 LAST VOLTAGE 6.3V
J 0
(-625 2250);
DISPLAY 0.638298 (-625 2250);
FORCEPROP 1 LAST $LOCATION C999
J 0
(-625 2350);
DISPLAY 0.638298 (-625 2350);
FORCEPROP 1 LASTPIN (-675 2350) $PN 1
J 0
(-665 2330);
DISPLAY 0.787234 (-665 2330);
FORCEPROP 1 LASTPIN (-675 2150) $PN 2
J 0
(-665 2130);
DISPLAY 0.787234 (-665 2130);
FORCEPROP 2 LAST CDS_LIB pure_quanta
J 0
(-675 2250);
PAINT MONO (-675 2250);
DISPLAY INVISIBLE (-675 2250);
FORCEPROP 2 LAST CDS_LOCATION C999
J 0
(-625 2450);
DISPLAY 1.021277 (-625 2450);
DISPLAY INVISIBLE (-625 2450);
FORCEPROP 2 LAST $SEC 1
J 0
(-625 2450);
DISPLAY 0.680851 (-625 2450);
PAINT MONO (-625 2450);
DISPLAY INVISIBLE (-625 2450);
FORCEPROP 2 LAST CDS_SEC 1
J 0
(-625 2450);
DISPLAY 1.021277 (-625 2450);
DISPLAY INVISIBLE (-625 2450);
FORCEPROP 1 LAST PATH I85
J 0
(-625 2400);
DISPLAY 0.978723 (-625 2400);
PAINT WHITE (-625 2400);
DISPLAY INVISIBLE (-625 2400);
FORCEADD Q_CAP..1
(-675 3025);
FORCEPROP 1 LAST PART_NUMBER CH6101MEB03
J 0
(-625 2875);
DISPLAY 0.638298 (-625 2875);
DISPLAY INVISIBLE (-625 2875);
FORCEPROP 1 LAST PACK_TYPE C0402
J 0
(-625 2825);
DISPLAY 0.638298 (-625 2825);
FORCEPROP 1 LAST MATERIAL X6S
J 0
(-625 2925);
DISPLAY 0.638298 (-625 2925);
FORCEPROP 1 LAST TOLERANCE 20%
J 0
(-625 2975);
DISPLAY 0.638298 (-625 2975);
FORCEPROP 1 LAST VALUE 10UF
J 0
(-625 3075);
DISPLAY 0.638298 (-625 3075);
FORCEPROP 1 LAST VOLTAGE 6.3V
J 0
(-625 3025);
DISPLAY 0.638298 (-625 3025);
FORCEPROP 1 LAST $LOCATION C998
J 0
(-625 3125);
DISPLAY 0.638298 (-625 3125);
FORCEPROP 1 LASTPIN (-675 3125) $PN 1
J 0
(-665 3105);
DISPLAY 0.787234 (-665 3105);
FORCEPROP 1 LASTPIN (-675 2925) $PN 2
J 0
(-665 2905);
DISPLAY 0.787234 (-665 2905);
FORCEPROP 2 LAST CDS_LIB pure_quanta
J 0
(-675 3025);
PAINT MONO (-675 3025);
DISPLAY INVISIBLE (-675 3025);
FORCEPROP 2 LAST CDS_LOCATION C998
J 0
(-625 3225);
DISPLAY 1.021277 (-625 3225);
DISPLAY INVISIBLE (-625 3225);
FORCEPROP 2 LAST $SEC 1
J 0
(-625 3225);
DISPLAY 0.680851 (-625 3225);
PAINT MONO (-625 3225);
DISPLAY INVISIBLE (-625 3225);
FORCEPROP 2 LAST CDS_SEC 1
J 0
(-625 3225);
DISPLAY 1.021277 (-625 3225);
DISPLAY INVISIBLE (-625 3225);
FORCEPROP 1 LAST PATH I86
J 0
(-625 3175);
DISPLAY 0.978723 (-625 3175);
PAINT WHITE (-625 3175);
DISPLAY INVISIBLE (-625 3175);
FORCEADD Q_CAP..1
(-225 2250);
FORCEPROP 1 LAST PART_NUMBER CH6101MEB03
J 0
(-175 2100);
DISPLAY 0.638298 (-175 2100);
DISPLAY INVISIBLE (-175 2100);
FORCEPROP 1 LAST PACK_TYPE C0402
J 0
(-175 2050);
DISPLAY 0.638298 (-175 2050);
FORCEPROP 1 LAST MATERIAL X6S
J 0
(-175 2150);
DISPLAY 0.638298 (-175 2150);
FORCEPROP 1 LAST TOLERANCE 20%
J 0
(-175 2200);
DISPLAY 0.638298 (-175 2200);
FORCEPROP 1 LAST VALUE 10UF
J 0
(-175 2300);
DISPLAY 0.638298 (-175 2300);
FORCEPROP 1 LAST VOLTAGE 6.3V
J 0
(-175 2250);
DISPLAY 0.638298 (-175 2250);
FORCEPROP 1 LAST $LOCATION C1003
J 0
(-175 2350);
DISPLAY 0.638298 (-175 2350);
FORCEPROP 1 LASTPIN (-225 2350) $PN 1
J 0
(-215 2330);
DISPLAY 0.787234 (-215 2330);
FORCEPROP 1 LASTPIN (-225 2150) $PN 2
J 0
(-215 2130);
DISPLAY 0.787234 (-215 2130);
FORCEPROP 2 LAST CDS_LIB pure_quanta
J 0
(-225 2250);
PAINT MONO (-225 2250);
DISPLAY INVISIBLE (-225 2250);
FORCEPROP 2 LAST CDS_LOCATION C1003
J 0
(-175 2450);
DISPLAY 1.021277 (-175 2450);
DISPLAY INVISIBLE (-175 2450);
FORCEPROP 2 LAST $SEC 1
J 0
(-175 2450);
DISPLAY 0.680851 (-175 2450);
PAINT MONO (-175 2450);
DISPLAY INVISIBLE (-175 2450);
FORCEPROP 2 LAST CDS_SEC 1
J 0
(-175 2450);
DISPLAY 1.021277 (-175 2450);
DISPLAY INVISIBLE (-175 2450);
FORCEPROP 1 LAST PATH I87
J 0
(-175 2400);
DISPLAY 0.978723 (-175 2400);
PAINT WHITE (-175 2400);
DISPLAY INVISIBLE (-175 2400);
FORCEADD UNIVERSAL_GND..1
(-225 2675);
FORCEPROP 3 LASTPIN (-225 2725) SIG_NAME GND\g
J 0
(-215 2735);
DISPLAY 0.659574 (-215 2735);
PAINT MONO (-215 2735);
DISPLAY INVISIBLE (-215 2735);
FORCEPROP 2 LAST CDS_LIB logical_power
J 0
(-225 2675);
PAINT MONO (-225 2675);
DISPLAY INVISIBLE (-225 2675);
FORCEPROP 1 LAST HDL_POWER GND
J 1
(-200 2600);
DISPLAY 0.872340 (-200 2600);
PAINT GREEN (-200 2600);
DISPLAY INVISIBLE (-200 2600);
FORCEPROP 1 LAST PATH I88
J 0
(-150 2675);
DISPLAY 0.872340 (-150 2675);
PAINT AQUA (-150 2675);
DISPLAY INVISIBLE (-150 2675);
FORCEADD Q_CAP..1
(-225 3025);
FORCEPROP 1 LAST PART_NUMBER CH6101MEB03
J 0
(-175 2875);
DISPLAY 0.638298 (-175 2875);
DISPLAY INVISIBLE (-175 2875);
FORCEPROP 1 LAST PACK_TYPE C0402
J 0
(-175 2825);
DISPLAY 0.638298 (-175 2825);
FORCEPROP 1 LAST MATERIAL X6S
J 0
(-175 2925);
DISPLAY 0.638298 (-175 2925);
FORCEPROP 1 LAST TOLERANCE 20%
J 0
(-175 2975);
DISPLAY 0.638298 (-175 2975);
FORCEPROP 1 LAST VALUE 10UF
J 0
(-175 3075);
DISPLAY 0.638298 (-175 3075);
FORCEPROP 1 LAST VOLTAGE 6.3V
J 0
(-175 3025);
DISPLAY 0.638298 (-175 3025);
FORCEPROP 1 LAST $LOCATION C1002
J 0
(-175 3125);
DISPLAY 0.638298 (-175 3125);
FORCEPROP 1 LASTPIN (-225 3125) $PN 1
J 0
(-215 3105);
DISPLAY 0.787234 (-215 3105);
FORCEPROP 1 LASTPIN (-225 2925) $PN 2
J 0
(-215 2905);
DISPLAY 0.787234 (-215 2905);
FORCEPROP 2 LAST CDS_LIB pure_quanta
J 0
(-225 3025);
PAINT MONO (-225 3025);
DISPLAY INVISIBLE (-225 3025);
FORCEPROP 2 LAST CDS_LOCATION C1002
J 0
(-175 3225);
DISPLAY 1.021277 (-175 3225);
DISPLAY INVISIBLE (-175 3225);
FORCEPROP 2 LAST $SEC 1
J 0
(-175 3225);
DISPLAY 0.680851 (-175 3225);
PAINT MONO (-175 3225);
DISPLAY INVISIBLE (-175 3225);
FORCEPROP 2 LAST CDS_SEC 1
J 0
(-175 3225);
DISPLAY 1.021277 (-175 3225);
DISPLAY INVISIBLE (-175 3225);
FORCEPROP 1 LAST PATH I89
J 0
(-175 3175);
DISPLAY 0.978723 (-175 3175);
PAINT WHITE (-175 3175);
DISPLAY INVISIBLE (-175 3175);
FORCEADD Q_CAP..1
(-1550 -1650);
FORCEPROP 1 LAST PART_NUMBER CH622KMEB01
J 0
(-1500 -1800);
DISPLAY 0.638298 (-1500 -1800);
DISPLAY INVISIBLE (-1500 -1800);
FORCEPROP 1 LAST MATERIAL X6S
J 0
(-1500 -1750);
DISPLAY 0.638298 (-1500 -1750);
FORCEPROP 1 LAST PACK_TYPE C0402
J 0
(-1500 -1850);
DISPLAY 0.638298 (-1500 -1850);
FORCEPROP 1 LAST TOLERANCE 20%
J 0
(-1500 -1700);
DISPLAY 0.638298 (-1500 -1700);
FORCEPROP 1 LAST VOLTAGE 4V
J 0
(-1500 -1650);
DISPLAY 0.638298 (-1500 -1650);
FORCEPROP 1 LAST VALUE 22UF
J 0
(-1500 -1600);
DISPLAY 0.638298 (-1500 -1600);
FORCEPROP 1 LAST $LOCATION C411
J 0
(-1500 -1550);
DISPLAY 0.978723 (-1500 -1550);
FORCEPROP 1 LASTPIN (-1550 -1550) $PN 1
J 0
(-1540 -1570);
DISPLAY 0.787234 (-1540 -1570);
FORCEPROP 1 LASTPIN (-1550 -1750) $PN 2
J 0
(-1540 -1770);
DISPLAY 0.787234 (-1540 -1770);
FORCEPROP 2 LAST CDS_LIB pure_quanta
J 0
(-1550 -1650);
PAINT MONO (-1550 -1650);
DISPLAY INVISIBLE (-1550 -1650);
FORCEPROP 2 LAST CDS_LOCATION C411
J 0
(-1500 -1450);
DISPLAY 1.021277 (-1500 -1450);
DISPLAY INVISIBLE (-1500 -1450);
FORCEPROP 2 LAST $SEC 1
J 0
(-1500 -1450);
DISPLAY 0.680851 (-1500 -1450);
PAINT MONO (-1500 -1450);
DISPLAY INVISIBLE (-1500 -1450);
FORCEPROP 2 LAST CDS_SEC 1
J 0
(-1500 -1450);
DISPLAY 1.021277 (-1500 -1450);
DISPLAY INVISIBLE (-1500 -1450);
FORCEPROP 1 LAST PATH I9
J 0
(-1500 -1500);
DISPLAY 0.978723 (-1500 -1500);
PAINT WHITE (-1500 -1500);
DISPLAY INVISIBLE (-1500 -1500);
FORCEADD Q_CAP..1
(275 1500);
FORCEPROP 1 LAST PART_NUMBER CH622KMEB01
J 0
(325 1350);
DISPLAY 0.638298 (325 1350);
DISPLAY INVISIBLE (325 1350);
FORCEPROP 1 LAST MATERIAL X6S
J 0
(325 1400);
DISPLAY 0.638298 (325 1400);
FORCEPROP 1 LAST PACK_TYPE C0402
J 0
(325 1300);
DISPLAY 0.638298 (325 1300);
FORCEPROP 1 LAST VOLTAGE 4V
J 0
(325 1500);
DISPLAY 0.638298 (325 1500);
FORCEPROP 1 LAST TOLERANCE 20%
J 0
(325 1450);
DISPLAY 0.638298 (325 1450);
FORCEPROP 1 LAST VALUE 22UF
J 0
(325 1550);
DISPLAY 0.638298 (325 1550);
FORCEPROP 1 LAST $LOCATION C1008
J 0
(325 1600);
DISPLAY 0.638298 (325 1600);
FORCEPROP 1 LASTPIN (275 1600) $PN 1
J 0
(285 1580);
DISPLAY 0.787234 (285 1580);
FORCEPROP 1 LASTPIN (275 1400) $PN 2
J 0
(285 1380);
DISPLAY 0.787234 (285 1380);
FORCEPROP 2 LAST CDS_LIB pure_quanta
J 0
(275 1500);
PAINT MONO (275 1500);
DISPLAY INVISIBLE (275 1500);
FORCEPROP 2 LAST CDS_LOCATION C1008
J 0
(325 1700);
DISPLAY 1.021277 (325 1700);
DISPLAY INVISIBLE (325 1700);
FORCEPROP 2 LAST $SEC 1
J 0
(325 1700);
DISPLAY 0.680851 (325 1700);
PAINT MONO (325 1700);
DISPLAY INVISIBLE (325 1700);
FORCEPROP 2 LAST CDS_SEC 1
J 0
(325 1700);
DISPLAY 1.021277 (325 1700);
DISPLAY INVISIBLE (325 1700);
FORCEPROP 1 LAST PATH I90
J 0
(325 1650);
DISPLAY 0.978723 (325 1650);
PAINT WHITE (325 1650);
DISPLAY INVISIBLE (325 1650);
FORCEADD UNIVERSAL_POWER..1
(275 1775);
FORCEPROP 3 LASTPIN (275 1725) SIG_NAME PVCCIN_CPU0\g
J 0
(285 1735);
DISPLAY 0.659574 (285 1735);
PAINT MONO (285 1735);
DISPLAY INVISIBLE (285 1735);
FORCEPROP 1 LAST HDL_POWER PVCCIN_CPU0
J 1
(475 1825);
DISPLAY 0.872340 (475 1825);
PAINT GREEN (475 1825);
FORCEPROP 2 LAST CDS_LIB logical_power
J 0
(275 1775);
DISPLAY INVISIBLE (275 1775);
FORCEPROP 1 LAST PATH I91
J 0
(325 1800);
DISPLAY 0.872340 (325 1800);
PAINT AQUA (325 1800);
DISPLAY INVISIBLE (325 1800);
FORCEADD Q_CAP..1
(725 1500);
FORCEPROP 1 LAST PART_NUMBER CH622KMEB01
J 0
(775 1350);
DISPLAY 0.638298 (775 1350);
DISPLAY INVISIBLE (775 1350);
FORCEPROP 1 LAST PACK_TYPE C0402
J 0
(775 1300);
DISPLAY 0.638298 (775 1300);
FORCEPROP 1 LAST MATERIAL X6S
J 0
(775 1400);
DISPLAY 0.638298 (775 1400);
FORCEPROP 1 LAST VOLTAGE 4V
J 0
(775 1500);
DISPLAY 0.638298 (775 1500);
FORCEPROP 1 LAST VALUE 22UF
J 0
(775 1550);
DISPLAY 0.638298 (775 1550);
FORCEPROP 1 LAST TOLERANCE 20%
J 0
(775 1450);
DISPLAY 0.638298 (775 1450);
FORCEPROP 1 LAST $LOCATION C1012
J 0
(775 1600);
DISPLAY 0.638298 (775 1600);
FORCEPROP 1 LASTPIN (725 1600) $PN 1
J 0
(735 1580);
DISPLAY 0.787234 (735 1580);
FORCEPROP 1 LASTPIN (725 1400) $PN 2
J 0
(735 1380);
DISPLAY 0.787234 (735 1380);
FORCEPROP 2 LAST CDS_LIB pure_quanta
J 0
(725 1500);
PAINT MONO (725 1500);
DISPLAY INVISIBLE (725 1500);
FORCEPROP 2 LAST CDS_LOCATION C1012
J 0
(775 1700);
DISPLAY 1.021277 (775 1700);
DISPLAY INVISIBLE (775 1700);
FORCEPROP 2 LAST $SEC 1
J 0
(775 1700);
DISPLAY 0.680851 (775 1700);
PAINT MONO (775 1700);
DISPLAY INVISIBLE (775 1700);
FORCEPROP 2 LAST CDS_SEC 1
J 0
(775 1700);
DISPLAY 1.021277 (775 1700);
DISPLAY INVISIBLE (775 1700);
FORCEPROP 1 LAST PATH I92
J 0
(775 1650);
DISPLAY 0.978723 (775 1650);
PAINT WHITE (775 1650);
DISPLAY INVISIBLE (775 1650);
FORCEADD Q_CAP..1
(250 2250);
FORCEPROP 1 LAST PART_NUMBER CH622KMEB01
J 0
(300 2100);
DISPLAY 0.638298 (300 2100);
DISPLAY INVISIBLE (300 2100);
FORCEPROP 1 LAST MATERIAL X6S
J 0
(300 2150);
DISPLAY 0.638298 (300 2150);
FORCEPROP 1 LAST VALUE 22UF
J 0
(300 2300);
DISPLAY 0.638298 (300 2300);
FORCEPROP 1 LAST PACK_TYPE C0402
J 0
(300 2050);
DISPLAY 0.638298 (300 2050);
FORCEPROP 1 LAST TOLERANCE 20%
J 0
(300 2200);
DISPLAY 0.638298 (300 2200);
FORCEPROP 1 LAST VOLTAGE 4V
J 0
(300 2250);
DISPLAY 0.638298 (300 2250);
FORCEPROP 1 LAST $LOCATION C1007
J 0
(300 2350);
DISPLAY 0.638298 (300 2350);
FORCEPROP 1 LASTPIN (250 2350) $PN 1
J 0
(260 2330);
DISPLAY 0.787234 (260 2330);
FORCEPROP 1 LASTPIN (250 2150) $PN 2
J 0
(260 2130);
DISPLAY 0.787234 (260 2130);
FORCEPROP 2 LAST CDS_LIB pure_quanta
J 0
(250 2250);
PAINT MONO (250 2250);
DISPLAY INVISIBLE (250 2250);
FORCEPROP 2 LAST CDS_LOCATION C1007
J 0
(300 2450);
DISPLAY 1.021277 (300 2450);
DISPLAY INVISIBLE (300 2450);
FORCEPROP 2 LAST $SEC 1
J 0
(300 2450);
DISPLAY 0.680851 (300 2450);
PAINT MONO (300 2450);
DISPLAY INVISIBLE (300 2450);
FORCEPROP 2 LAST CDS_SEC 1
J 0
(300 2450);
DISPLAY 1.021277 (300 2450);
DISPLAY INVISIBLE (300 2450);
FORCEPROP 1 LAST PATH I93
J 0
(300 2400);
DISPLAY 0.978723 (300 2400);
PAINT WHITE (300 2400);
DISPLAY INVISIBLE (300 2400);
FORCEADD UNIVERSAL_POWER..1
(250 2525);
FORCEPROP 3 LASTPIN (250 2475) SIG_NAME PVCCIN_CPU0\g
J 0
(260 2485);
DISPLAY 0.659574 (260 2485);
PAINT MONO (260 2485);
DISPLAY INVISIBLE (260 2485);
FORCEPROP 1 LAST HDL_POWER PVCCIN_CPU0
J 1
(450 2575);
DISPLAY 0.872340 (450 2575);
PAINT GREEN (450 2575);
FORCEPROP 2 LAST CDS_LIB logical_power
J 0
(250 2525);
DISPLAY INVISIBLE (250 2525);
FORCEPROP 1 LAST PATH I94
J 0
(300 2550);
DISPLAY 0.872340 (300 2550);
PAINT AQUA (300 2550);
DISPLAY INVISIBLE (300 2550);
FORCEADD Q_CAP..1
(250 3025);
FORCEPROP 1 LAST PART_NUMBER CH622KMEB01
J 0
(300 2875);
DISPLAY 0.638298 (300 2875);
DISPLAY INVISIBLE (300 2875);
FORCEPROP 1 LAST MATERIAL X6S
J 0
(300 2925);
DISPLAY 0.638298 (300 2925);
FORCEPROP 1 LAST PACK_TYPE C0402
J 0
(300 2825);
DISPLAY 0.638298 (300 2825);
FORCEPROP 1 LAST TOLERANCE 20%
J 0
(300 2975);
DISPLAY 0.638298 (300 2975);
FORCEPROP 1 LAST VALUE 22UF
J 0
(300 3075);
DISPLAY 0.638298 (300 3075);
FORCEPROP 1 LAST VOLTAGE 4V
J 0
(300 3025);
DISPLAY 0.638298 (300 3025);
FORCEPROP 1 LAST $LOCATION C1006
J 0
(300 3125);
DISPLAY 0.638298 (300 3125);
FORCEPROP 1 LASTPIN (250 3125) $PN 1
J 0
(260 3105);
DISPLAY 0.787234 (260 3105);
FORCEPROP 1 LASTPIN (250 2925) $PN 2
J 0
(260 2905);
DISPLAY 0.787234 (260 2905);
FORCEPROP 2 LAST CDS_LIB pure_quanta
J 0
(250 3025);
PAINT MONO (250 3025);
DISPLAY INVISIBLE (250 3025);
FORCEPROP 2 LAST CDS_LOCATION C1006
J 0
(300 3225);
DISPLAY 1.021277 (300 3225);
DISPLAY INVISIBLE (300 3225);
FORCEPROP 2 LAST $SEC 1
J 0
(300 3225);
DISPLAY 0.680851 (300 3225);
PAINT MONO (300 3225);
DISPLAY INVISIBLE (300 3225);
FORCEPROP 2 LAST CDS_SEC 1
J 0
(300 3225);
DISPLAY 1.021277 (300 3225);
DISPLAY INVISIBLE (300 3225);
FORCEPROP 1 LAST PATH I95
J 0
(300 3175);
DISPLAY 0.978723 (300 3175);
PAINT WHITE (300 3175);
DISPLAY INVISIBLE (300 3175);
FORCEADD Q_CAP..1
(700 2250);
FORCEPROP 1 LAST PART_NUMBER CH622KMEB01
J 0
(750 2100);
DISPLAY 0.638298 (750 2100);
DISPLAY INVISIBLE (750 2100);
FORCEPROP 1 LAST MATERIAL X6S
J 0
(750 2150);
DISPLAY 0.638298 (750 2150);
FORCEPROP 1 LAST PACK_TYPE C0402
J 0
(750 2050);
DISPLAY 0.638298 (750 2050);
FORCEPROP 1 LAST VALUE 22UF
J 0
(750 2300);
DISPLAY 0.638298 (750 2300);
FORCEPROP 1 LAST TOLERANCE 20%
J 0
(750 2200);
DISPLAY 0.638298 (750 2200);
FORCEPROP 1 LAST VOLTAGE 4V
J 0
(750 2250);
DISPLAY 0.638298 (750 2250);
FORCEPROP 1 LAST $LOCATION C1011
J 0
(750 2350);
DISPLAY 0.638298 (750 2350);
FORCEPROP 1 LASTPIN (700 2350) $PN 1
J 0
(710 2330);
DISPLAY 0.787234 (710 2330);
FORCEPROP 1 LASTPIN (700 2150) $PN 2
J 0
(710 2130);
DISPLAY 0.787234 (710 2130);
FORCEPROP 2 LAST CDS_LIB pure_quanta
J 0
(700 2250);
PAINT MONO (700 2250);
DISPLAY INVISIBLE (700 2250);
FORCEPROP 2 LAST CDS_LOCATION C1011
J 0
(750 2450);
DISPLAY 1.021277 (750 2450);
DISPLAY INVISIBLE (750 2450);
FORCEPROP 2 LAST $SEC 1
J 0
(750 2450);
DISPLAY 0.680851 (750 2450);
PAINT MONO (750 2450);
DISPLAY INVISIBLE (750 2450);
FORCEPROP 2 LAST CDS_SEC 1
J 0
(750 2450);
DISPLAY 1.021277 (750 2450);
DISPLAY INVISIBLE (750 2450);
FORCEPROP 1 LAST PATH I96
J 0
(750 2400);
DISPLAY 0.978723 (750 2400);
PAINT WHITE (750 2400);
DISPLAY INVISIBLE (750 2400);
FORCEADD Q_CAP..1
(700 3025);
FORCEPROP 1 LAST PART_NUMBER CH622KMEB01
J 0
(750 2875);
DISPLAY 0.638298 (750 2875);
DISPLAY INVISIBLE (750 2875);
FORCEPROP 1 LAST MATERIAL X6S
J 0
(750 2925);
DISPLAY 0.638298 (750 2925);
FORCEPROP 1 LAST PACK_TYPE C0402
J 0
(750 2825);
DISPLAY 0.638298 (750 2825);
FORCEPROP 1 LAST TOLERANCE 20%
J 0
(750 2975);
DISPLAY 0.638298 (750 2975);
FORCEPROP 1 LAST VALUE 22UF
J 0
(750 3075);
DISPLAY 0.638298 (750 3075);
FORCEPROP 1 LAST VOLTAGE 4V
J 0
(750 3025);
DISPLAY 0.638298 (750 3025);
FORCEPROP 1 LAST $LOCATION C1010
J 0
(750 3125);
DISPLAY 0.638298 (750 3125);
FORCEPROP 1 LASTPIN (700 3125) $PN 1
J 0
(710 3105);
DISPLAY 0.787234 (710 3105);
FORCEPROP 1 LASTPIN (700 2925) $PN 2
J 0
(710 2905);
DISPLAY 0.787234 (710 2905);
FORCEPROP 2 LAST CDS_LIB pure_quanta
J 0
(700 3025);
PAINT MONO (700 3025);
DISPLAY INVISIBLE (700 3025);
FORCEPROP 2 LAST CDS_LOCATION C1010
J 0
(750 3225);
DISPLAY 1.021277 (750 3225);
DISPLAY INVISIBLE (750 3225);
FORCEPROP 2 LAST $SEC 1
J 0
(750 3225);
DISPLAY 0.680851 (750 3225);
PAINT MONO (750 3225);
DISPLAY INVISIBLE (750 3225);
FORCEPROP 2 LAST CDS_SEC 1
J 0
(750 3225);
DISPLAY 1.021277 (750 3225);
DISPLAY INVISIBLE (750 3225);
FORCEPROP 1 LAST PATH I97
J 0
(750 3175);
DISPLAY 0.978723 (750 3175);
PAINT WHITE (750 3175);
DISPLAY INVISIBLE (750 3175);
FORCEADD Q_CAP..1
(1025 -850);
FORCEPROP 1 LAST PART_NUMBER CH622KMEB01
J 0
(1075 -1000);
DISPLAY 0.638298 (1075 -1000);
DISPLAY INVISIBLE (1075 -1000);
FORCEPROP 1 LAST PACK_TYPE C0402
J 0
(1075 -1050);
DISPLAY 0.638298 (1075 -1050);
FORCEPROP 1 LAST MATERIAL X6S
J 0
(1075 -950);
DISPLAY 0.638298 (1075 -950);
FORCEPROP 1 LAST TOLERANCE 20%
J 0
(1075 -900);
DISPLAY 0.638298 (1075 -900);
FORCEPROP 1 LAST VOLTAGE 4V
J 0
(1075 -850);
DISPLAY 0.638298 (1075 -850);
FORCEPROP 1 LAST VALUE 22UF
J 0
(1075 -800);
DISPLAY 0.638298 (1075 -800);
FORCEPROP 1 LAST $LOCATION C419
J 0
(1075 -750);
DISPLAY 0.978723 (1075 -750);
FORCEPROP 1 LASTPIN (1025 -750) $PN 1
J 0
(1035 -770);
DISPLAY 0.787234 (1035 -770);
FORCEPROP 1 LASTPIN (1025 -950) $PN 2
J 0
(1035 -970);
DISPLAY 0.787234 (1035 -970);
FORCEPROP 2 LAST CDS_LIB pure_quanta
J 0
(1025 -850);
PAINT MONO (1025 -850);
DISPLAY INVISIBLE (1025 -850);
FORCEPROP 2 LAST CDS_LOCATION C419
J 0
(1075 -650);
DISPLAY 1.021277 (1075 -650);
DISPLAY INVISIBLE (1075 -650);
FORCEPROP 2 LAST $SEC 1
J 0
(1075 -650);
DISPLAY 0.680851 (1075 -650);
PAINT MONO (1075 -650);
DISPLAY INVISIBLE (1075 -650);
FORCEPROP 2 LAST CDS_SEC 1
J 0
(1075 -650);
DISPLAY 1.021277 (1075 -650);
DISPLAY INVISIBLE (1075 -650);
FORCEPROP 1 LAST PATH I98
J 0
(1075 -700);
DISPLAY 0.978723 (1075 -700);
PAINT WHITE (1075 -700);
DISPLAY INVISIBLE (1075 -700);
FORCEADD UNIVERSAL_POWER..1
(1025 -575);
FORCEPROP 3 LASTPIN (1025 -625) SIG_NAME PVCCFA_EHV_CPU0\g
J 0
(1035 -615);
DISPLAY 0.659574 (1035 -615);
PAINT MONO (1035 -615);
DISPLAY INVISIBLE (1035 -615);
FORCEPROP 1 LAST HDL_POWER PVCCFA_EHV_CPU0
J 1
(1075 -525);
DISPLAY 1.085106 (1075 -525);
PAINT GREEN (1075 -525);
FORCEPROP 2 LAST CDS_LIB logical_power
J 0
(1025 -575);
PAINT MONO (1025 -575);
DISPLAY INVISIBLE (1025 -575);
FORCEPROP 1 LAST PATH I99
J 0
(1075 -550);
DISPLAY 0.872340 (1075 -550);
PAINT AQUA (1075 -550);
DISPLAY INVISIBLE (1075 -550);
FORCEADD QUANTA_TITLE_BLOCK_C..1
(4825 -2775);
FORCEPROP 0 LAST CDS_CON_LAST_MODIFIED Fri Aug 25 14:00:54 2023
J 0
(2940 -2760);
PAINT MONO (2940 -2760);
DISPLAY INVISIBLE (2940 -2760);
FORCEPROP 2 LAST CUSTOM_TXT_CDS <XR_PAGE_TITLE>
J 0
(-3065 2475);
DISPLAY 0.638298 (-3065 2475);
PAINT PINK (-3065 2475);
DISPLAY INVISIBLE (-3065 2475);
FORCEPROP 2 LAST CUSTOM_TXT_CDS <CON_PAGE_NUM> OF <CON_TOTAL_PAGES>
J 0
(4400 -2775);
DISPLAY 0.978723 (4400 -2775);
FORCEPROP 2 LAST CUSTOM_TXT_CDS <Q_REV>
J 0
(4641 -2672);
DISPLAY 1.212766 (4641 -2672);
FORCEPROP 2 LAST CUSTOM_TXT_CDS <CON_LAST_MODIFIED>
J 0
(2975 -2750);
DISPLAY 0.978723 (2975 -2750);
FORCEPROP 2 LAST CUSTOM_TXT_CDS <Q_NUMBER>
J 0
(3422 -2672);
DISPLAY 1.212766 (3422 -2672);
FORCEPROP 2 LAST CUSTOM_TXT_CDS <NAME_2>
J 0
(1650 -2725);
FORCEPROP 2 LAST CUSTOM_TXT_CDS <NAME_1>
J 0
(1650 -2600);
FORCEPROP 2 LAST CUSTOM_TXT_CDS <Q_PROJ>
J 0
(2443 -2673);
DISPLAY 1.212766 (2443 -2673);
FORCEPROP 1 LAST Q_TITLE SPR CPU0 TOP DECOUPLING CAPS
J 0
(-4516 -2749);
DISPLAY 1.957447 (-4516 -2749);
PAINT GREEN (-4516 -2749);
FORCEPROP 1 LAST Q_DEPT 
J 1
(1062 -2726);
DISPLAY 1.957447 (1062 -2726);
PAINT GREEN (1062 -2726);
FORCEPROP 1 LAST COMMENT_BODY TRUE
J 0
(4837 -2788);
DISPLAY 0.978723 (4837 -2788);
PAINT GREEN (4837 -2788);
DISPLAY INVISIBLE (4837 -2788);
FORCEPROP 2 LAST CDS_XR_PAGE_TITLE CR-74 : @S9S_MB_2U_LIB.S9S_MB_2U(SCH_1):PAGE74
J 0
(-3065 2475);
DISPLAY 0.638298 (-3065 2475);
PAINT PINK (-3065 2475);
DISPLAY INVISIBLE (-3065 2475);
FORCEPROP 2 LAST CDS_LIB pure_quanta
J 0
(4825 -2775);
PAINT MONO (4825 -2775);
DISPLAY INVISIBLE (4825 -2775);
FORCEPROP 1 LAST CDS_LMAN_SYM_OUTLINE -9475,6775,100,-125
J 0
(4825 -2775);
DISPLAY 0.468085 (4825 -2775);
PAINT GREEN (4825 -2775);
DISPLAY INVISIBLE (4825 -2775);
FORCEPROP 2 LAST PAGE_BORDER TRUE
J 0
(-3065 2475);
DISPLAY 0.638298 (-3065 2475);
PAINT PINK (-3065 2475);
DISPLAY INVISIBLE (-3065 2475);
WIRE 16 -1 (1025 -675)(1025 -625);
WIRE 16 -1 (1475 -675)(1025 -675);
WIRE 16 -1 (1025 -675)(1025 -750);
WIRE 16 -1 (-4250 900)(-4250 950);
WIRE 16 -1 (-3800 900)(-4250 900);
WIRE 16 -1 (-4250 900)(-4250 825);
WIRE 16 -1 (250 3200)(250 3250);
WIRE 16 -1 (700 3200)(250 3200);
WIRE 16 -1 (250 3200)(250 3125);
WIRE 16 -1 (1025 75)(1025 -50);
WIRE 16 -1 (250 2425)(250 2475);
WIRE 16 -1 (700 2425)(250 2425);
WIRE 16 -1 (250 2425)(250 2350);
WIRE 16 -1 (275 1675)(275 1725);
WIRE 16 -1 (725 1675)(275 1675);
WIRE 16 -1 (275 1675)(275 1600);
WIRE 16 -1 (275 900)(275 950);
WIRE 16 -1 (725 900)(275 900);
WIRE 16 -1 (275 900)(275 825);
WIRE 16 -1 (-2000 -675)(-2000 -625);
WIRE 16 -1 (-1550 -675)(-2000 -675);
WIRE 16 -1 (-2000 -675)(-2000 -750);
WIRE 16 -1 (-4275 2425)(-4275 2475);
WIRE 16 -1 (-3825 2425)(-4275 2425);
WIRE 16 -1 (-4275 2425)(-4275 2350);
WIRE 16 -1 (-4250 1675)(-4250 1725);
WIRE 16 -1 (-3800 1675)(-4250 1675);
WIRE 16 -1 (-4250 1675)(-4250 1600);
WIRE 16 -1 (-4250 125)(-4250 175);
WIRE 16 -1 (-3800 125)(-4250 125);
WIRE 16 -1 (-4250 125)(-4250 50);
WIRE 16 -1 (-4250 -675)(-4250 -625);
WIRE 16 -1 (-3800 -675)(-4250 -675);
WIRE 16 -1 (-4250 -675)(-4250 -750);
WIRE 16 -1 (-4275 3200)(-4275 3250);
WIRE 16 -1 (-3825 3200)(-4275 3200);
WIRE 16 -1 (-4275 3200)(-4275 3125);
WIRE 16 -1 (-4250 -1475)(-4250 -1425);
WIRE 16 -1 (-3800 -1475)(-4250 -1475);
WIRE 16 -1 (-4250 -1475)(-4250 -1550);
WIRE 16 -1 (4300 1950)(4300 2025);
WIRE 16 -1 (4325 1200)(4325 1275);
WIRE 16 -1 (3850 2725)(3850 2800);
WIRE 16 -1 (4325 425)(4325 500);
WIRE 16 -1 (1025 -375)(1025 -250);
WIRE 16 -1 (-225 2725)(-225 2800);
WIRE 16 -1 (-225 1950)(-225 2025);
WIRE 16 -1 (-200 1200)(-200 1275);
WIRE 16 -1 (-200 425)(-200 500);
WIRE 16 -1 (-200 -350)(-200 -275);
WIRE 16 -1 (2375 -1125)(2375 -1075);
WIRE 16 -1 (250 -1950)(250 -1875);
WIRE 16 -1 (-200 -1150)(-200 -1075);
WIRE 16 -1 (-2900 -1125)(-2900 -1075);
WIRE 16 -1 (1025 -1075)(1025 -950);
WIRE 16 -1 (1475 -1075)(1025 -1075);
WIRE 16 -1 (1475 -1075)(1475 -950);
WIRE 16 -1 (1925 -1075)(1475 -1075);
WIRE 16 -1 (1925 -1075)(1925 -950);
WIRE 16 -1 (2375 -1075)(1925 -1075);
WIRE 16 -1 (2375 -950)(2375 -1075);
WIRE 16 -1 (1475 -750)(1475 -675);
WIRE 16 -1 (1925 -675)(1475 -675);
WIRE 16 -1 (1925 -675)(1925 -750);
WIRE 16 -1 (2375 -675)(1925 -675);
WIRE 16 -1 (2375 -750)(2375 -675);
WIRE 16 -1 (-200 500)(-200 625);
WIRE 16 -1 (-650 500)(-650 625);
WIRE 16 -1 (-200 500)(-650 500);
WIRE 16 -1 (-1100 500)(-1100 625);
WIRE 16 -1 (-650 500)(-1100 500);
WIRE 16 -1 (-4250 500)(-4250 625);
WIRE 16 -1 (-3800 500)(-4250 500);
WIRE 16 -1 (-3800 500)(-3800 625);
WIRE 16 -1 (-1550 500)(-1550 625);
WIRE 16 -1 (-1100 500)(-1550 500);
WIRE 16 -1 (-1550 500)(-2000 500);
WIRE 16 -1 (-2000 500)(-2000 625);
WIRE 16 -1 (-3350 500)(-3800 500);
WIRE 16 -1 (-3350 500)(-3350 625);
WIRE 16 -1 (-2900 500)(-3350 500);
WIRE 16 -1 (-2900 500)(-2900 625);
WIRE 16 -1 (-2450 500)(-2450 625);
WIRE 16 -1 (-2000 500)(-2450 500);
WIRE 16 -1 (-2450 500)(-2900 500);
WIRE 16 -1 (-200 825)(-200 900);
WIRE 16 -1 (-650 900)(-650 825);
WIRE 16 -1 (-200 900)(-650 900);
WIRE 16 -1 (-1100 825)(-1100 900);
WIRE 16 -1 (-650 900)(-1100 900);
WIRE 16 -1 (-1550 825)(-1550 900);
WIRE 16 -1 (-1100 900)(-1550 900);
WIRE 16 -1 (-2000 900)(-2000 825);
WIRE 16 -1 (-1550 900)(-2000 900);
WIRE 16 -1 (-2450 825)(-2450 900);
WIRE 16 -1 (-2000 900)(-2450 900);
WIRE 16 -1 (-2900 825)(-2900 900);
WIRE 16 -1 (-2450 900)(-2900 900);
WIRE 16 -1 (-3350 900)(-3350 825);
WIRE 16 -1 (-2900 900)(-3350 900);
WIRE 16 -1 (-3350 900)(-3800 900);
WIRE 16 -1 (-3800 825)(-3800 900);
WIRE 16 -1 (-3800 -750)(-3800 -675);
WIRE 16 -1 (-3350 -675)(-3800 -675);
WIRE 16 -1 (-3350 -675)(-3350 -750);
WIRE 16 -1 (-2900 -675)(-3350 -675);
WIRE 16 -1 (-2900 -750)(-2900 -675);
WIRE 16 -1 (-200 -275)(-200 -150);
WIRE 16 -1 (-650 -275)(-650 -150);
WIRE 16 -1 (-200 -275)(-650 -275);
WIRE 16 -1 (-1100 -275)(-1100 -150);
WIRE 16 -1 (-650 -275)(-1100 -275);
WIRE 16 -1 (-4250 -275)(-4250 -150);
WIRE 16 -1 (-3800 -275)(-4250 -275);
WIRE 16 -1 (-3800 -275)(-3800 -150);
WIRE 16 -1 (-1550 -275)(-1550 -150);
WIRE 16 -1 (-1100 -275)(-1550 -275);
WIRE 16 -1 (-2000 -275)(-2000 -150);
WIRE 16 -1 (-1550 -275)(-2000 -275);
WIRE 16 -1 (-3350 -275)(-3800 -275);
WIRE 16 -1 (-3350 -275)(-3350 -150);
WIRE 16 -1 (-2900 -275)(-3350 -275);
WIRE 16 -1 (-2900 -275)(-2900 -150);
WIRE 16 -1 (-2450 -275)(-2450 -150);
WIRE 16 -1 (-2000 -275)(-2450 -275);
WIRE 16 -1 (-2450 -275)(-2900 -275);
WIRE 16 -1 (-1550 -750)(-1550 -675);
WIRE 16 -1 (-1100 -675)(-1550 -675);
WIRE 16 -1 (-1100 -750)(-1100 -675);
WIRE 16 -1 (-650 -675)(-1100 -675);
WIRE 16 -1 (-650 -675)(-650 -750);
WIRE 16 -1 (-200 -675)(-650 -675);
WIRE 16 -1 (-200 -750)(-200 -675);
WIRE 16 -1 (-200 50)(-200 125);
WIRE 16 -1 (-650 125)(-650 50);
WIRE 16 -1 (-200 125)(-650 125);
WIRE 16 -1 (-1100 50)(-1100 125);
WIRE 16 -1 (-650 125)(-1100 125);
WIRE 16 -1 (-1550 50)(-1550 125);
WIRE 16 -1 (-1100 125)(-1550 125);
WIRE 16 -1 (-2000 125)(-2000 50);
WIRE 16 -1 (-1550 125)(-2000 125);
WIRE 16 -1 (-2450 50)(-2450 125);
WIRE 16 -1 (-2000 125)(-2450 125);
WIRE 16 -1 (-2900 50)(-2900 125);
WIRE 16 -1 (-2450 125)(-2900 125);
WIRE 16 -1 (-3350 125)(-3350 50);
WIRE 16 -1 (-2900 125)(-3350 125);
WIRE 16 -1 (-3350 125)(-3800 125);
WIRE 16 -1 (-3800 50)(-3800 125);
WIRE 16 -1 (-200 1275)(-200 1400);
WIRE 16 -1 (-650 1275)(-650 1400);
WIRE 16 -1 (-200 1275)(-650 1275);
WIRE 16 -1 (-1100 1275)(-1100 1400);
WIRE 16 -1 (-650 1275)(-1100 1275);
WIRE 16 -1 (-4250 1275)(-4250 1400);
WIRE 16 -1 (-3800 1275)(-4250 1275);
WIRE 16 -1 (-3800 1275)(-3800 1400);
WIRE 16 -1 (-1550 1275)(-1550 1400);
WIRE 16 -1 (-1100 1275)(-1550 1275);
WIRE 16 -1 (-2000 1275)(-2000 1400);
WIRE 16 -1 (-1550 1275)(-2000 1275);
WIRE 16 -1 (-3350 1275)(-3800 1275);
WIRE 16 -1 (-3350 1275)(-3350 1400);
WIRE 16 -1 (-2900 1275)(-3350 1275);
WIRE 16 -1 (-2900 1275)(-2900 1400);
WIRE 16 -1 (-2450 1275)(-2450 1400);
WIRE 16 -1 (-2000 1275)(-2450 1275);
WIRE 16 -1 (-2450 1275)(-2900 1275);
WIRE 16 -1 (-200 1600)(-200 1675);
WIRE 16 -1 (-650 1675)(-650 1600);
WIRE 16 -1 (-200 1675)(-650 1675);
WIRE 16 -1 (-1100 1600)(-1100 1675);
WIRE 16 -1 (-650 1675)(-1100 1675);
WIRE 16 -1 (-1550 1600)(-1550 1675);
WIRE 16 -1 (-1100 1675)(-1550 1675);
WIRE 16 -1 (-2000 1675)(-2000 1600);
WIRE 16 -1 (-1550 1675)(-2000 1675);
WIRE 16 -1 (-2450 1600)(-2450 1675);
WIRE 16 -1 (-2000 1675)(-2450 1675);
WIRE 16 -1 (-2900 1600)(-2900 1675);
WIRE 16 -1 (-2450 1675)(-2900 1675);
WIRE 16 -1 (-3350 1675)(-3350 1600);
WIRE 16 -1 (-2900 1675)(-3350 1675);
WIRE 16 -1 (-3350 1675)(-3800 1675);
WIRE 16 -1 (-3800 1600)(-3800 1675);
WIRE 16 -1 (-225 2800)(-225 2925);
WIRE 16 -1 (-675 2800)(-675 2925);
WIRE 16 -1 (-225 2800)(-675 2800);
WIRE 16 -1 (-1125 2800)(-1125 2925);
WIRE 16 -1 (-675 2800)(-1125 2800);
WIRE 16 -1 (-4275 2800)(-4275 2925);
WIRE 16 -1 (-3825 2800)(-4275 2800);
WIRE 16 -1 (-3825 2800)(-3825 2925);
WIRE 16 -1 (-1575 2800)(-1575 2925);
WIRE 16 -1 (-1125 2800)(-1575 2800);
WIRE 16 -1 (-2025 2800)(-2025 2925);
WIRE 16 -1 (-1575 2800)(-2025 2800);
WIRE 16 -1 (-3375 2800)(-3825 2800);
WIRE 16 -1 (-3375 2800)(-3375 2925);
WIRE 16 -1 (-2925 2800)(-3375 2800);
WIRE 16 -1 (-2925 2800)(-2925 2925);
WIRE 16 -1 (-2475 2800)(-2475 2925);
WIRE 16 -1 (-2025 2800)(-2475 2800);
WIRE 16 -1 (-2475 2800)(-2925 2800);
WIRE 16 -1 (-225 3125)(-225 3200);
WIRE 16 -1 (-675 3200)(-675 3125);
WIRE 16 -1 (-225 3200)(-675 3200);
WIRE 16 -1 (-1125 3125)(-1125 3200);
WIRE 16 -1 (-675 3200)(-1125 3200);
WIRE 16 -1 (-1575 3125)(-1575 3200);
WIRE 16 -1 (-1125 3200)(-1575 3200);
WIRE 16 -1 (-2025 3200)(-2025 3125);
WIRE 16 -1 (-1575 3200)(-2025 3200);
WIRE 16 -1 (-2475 3125)(-2475 3200);
WIRE 16 -1 (-2025 3200)(-2475 3200);
WIRE 16 -1 (-2925 3125)(-2925 3200);
WIRE 16 -1 (-2475 3200)(-2925 3200);
WIRE 16 -1 (-3375 3200)(-3375 3125);
WIRE 16 -1 (-2925 3200)(-3375 3200);
WIRE 16 -1 (-3375 3200)(-3825 3200);
WIRE 16 -1 (-3825 3125)(-3825 3200);
WIRE 16 -1 (275 500)(275 625);
WIRE 16 -1 (725 500)(275 500);
WIRE 16 -1 (725 500)(725 625);
WIRE 16 -1 (1175 500)(725 500);
WIRE 16 -1 (1175 500)(1175 625);
WIRE 16 -1 (1625 500)(1175 500);
WIRE 16 -1 (1625 500)(1625 625);
WIRE 16 -1 (2075 500)(1625 500);
WIRE 16 -1 (2075 500)(2075 625);
WIRE 16 -1 (2525 500)(2075 500);
WIRE 16 -1 (2525 500)(2525 625);
WIRE 16 -1 (2975 500)(2525 500);
WIRE 16 -1 (2975 500)(2975 625);
WIRE 16 -1 (3425 500)(2975 500);
WIRE 16 -1 (3425 500)(3425 625);
WIRE 16 -1 (3875 500)(3425 500);
WIRE 16 -1 (3875 500)(3875 625);
WIRE 16 -1 (4325 500)(3875 500);
WIRE 16 -1 (4325 500)(4325 625);
WIRE 16 -1 (4325 825)(4325 900);
WIRE 16 -1 (3875 900)(3875 825);
WIRE 16 -1 (4325 900)(3875 900);
WIRE 16 -1 (3425 825)(3425 900);
WIRE 16 -1 (3875 900)(3425 900);
WIRE 16 -1 (2975 825)(2975 900);
WIRE 16 -1 (3425 900)(2975 900);
WIRE 16 -1 (2525 900)(2525 825);
WIRE 16 -1 (2975 900)(2525 900);
WIRE 16 -1 (2075 825)(2075 900);
WIRE 16 -1 (2525 900)(2075 900);
WIRE 16 -1 (1625 825)(1625 900);
WIRE 16 -1 (2075 900)(1625 900);
WIRE 16 -1 (1175 900)(1175 825);
WIRE 16 -1 (1625 900)(1175 900);
WIRE 16 -1 (1175 900)(725 900);
WIRE 16 -1 (725 825)(725 900);
WIRE 16 -1 (3850 2800)(3850 2925);
WIRE 16 -1 (3400 2800)(3400 2925);
WIRE 16 -1 (3850 2800)(3400 2800);
WIRE 16 -1 (250 2800)(250 2925);
WIRE 16 -1 (700 2800)(250 2800);
WIRE 16 -1 (700 2800)(700 2925);
WIRE 16 -1 (2950 2800)(2950 2925);
WIRE 16 -1 (3400 2800)(2950 2800);
WIRE 16 -1 (2500 2800)(2500 2925);
WIRE 16 -1 (2950 2800)(2500 2800);
WIRE 16 -1 (1150 2800)(700 2800);
WIRE 16 -1 (1150 2800)(1150 2925);
WIRE 16 -1 (1600 2800)(1150 2800);
WIRE 16 -1 (1600 2800)(1600 2925);
WIRE 16 -1 (2050 2800)(2050 2925);
WIRE 16 -1 (2500 2800)(2050 2800);
WIRE 16 -1 (2050 2800)(1600 2800);
WIRE 16 -1 (4325 1600)(4325 1675);
WIRE 16 -1 (3875 1675)(3875 1600);
WIRE 16 -1 (4325 1675)(3875 1675);
WIRE 16 -1 (3425 1600)(3425 1675);
WIRE 16 -1 (3875 1675)(3425 1675);
WIRE 16 -1 (2975 1600)(2975 1675);
WIRE 16 -1 (3425 1675)(2975 1675);
WIRE 16 -1 (2525 1675)(2525 1600);
WIRE 16 -1 (2975 1675)(2525 1675);
WIRE 16 -1 (2075 1600)(2075 1675);
WIRE 16 -1 (2525 1675)(2075 1675);
WIRE 16 -1 (1625 1600)(1625 1675);
WIRE 16 -1 (2075 1675)(1625 1675);
WIRE 16 -1 (1175 1675)(1175 1600);
WIRE 16 -1 (1625 1675)(1175 1675);
WIRE 16 -1 (1175 1675)(725 1675);
WIRE 16 -1 (725 1600)(725 1675);
WIRE 16 -1 (4300 2350)(4300 2425);
WIRE 16 -1 (3850 2425)(3850 2350);
WIRE 16 -1 (4300 2425)(3850 2425);
WIRE 16 -1 (3400 2350)(3400 2425);
WIRE 16 -1 (3850 2425)(3400 2425);
WIRE 16 -1 (2950 2350)(2950 2425);
WIRE 16 -1 (3400 2425)(2950 2425);
WIRE 16 -1 (2500 2425)(2500 2350);
WIRE 16 -1 (2950 2425)(2500 2425);
WIRE 16 -1 (2050 2350)(2050 2425);
WIRE 16 -1 (2500 2425)(2050 2425);
WIRE 16 -1 (1600 2350)(1600 2425);
WIRE 16 -1 (2050 2425)(1600 2425);
WIRE 16 -1 (1150 2425)(1150 2350);
WIRE 16 -1 (1600 2425)(1150 2425);
WIRE 16 -1 (1150 2425)(700 2425);
WIRE 16 -1 (700 2350)(700 2425);
WIRE 16 -1 (250 2025)(250 2150);
WIRE 16 -1 (700 2025)(250 2025);
WIRE 16 -1 (700 2025)(700 2150);
WIRE 16 -1 (1150 2025)(700 2025);
WIRE 16 -1 (1150 2025)(1150 2150);
WIRE 16 -1 (1600 2025)(1150 2025);
WIRE 16 -1 (1600 2025)(1600 2150);
WIRE 16 -1 (2050 2025)(1600 2025);
WIRE 16 -1 (2050 2025)(2050 2150);
WIRE 16 -1 (2500 2025)(2050 2025);
WIRE 16 -1 (2500 2025)(2500 2150);
WIRE 16 -1 (2950 2025)(2500 2025);
WIRE 16 -1 (2950 2025)(2950 2150);
WIRE 16 -1 (3400 2025)(2950 2025);
WIRE 16 -1 (3400 2025)(3400 2150);
WIRE 16 -1 (3850 2025)(3400 2025);
WIRE 16 -1 (3850 2025)(3850 2150);
WIRE 16 -1 (4300 2025)(3850 2025);
WIRE 16 -1 (4300 2025)(4300 2150);
WIRE 16 -1 (3850 3200)(3850 3125);
WIRE 16 -1 (3400 3125)(3400 3200);
WIRE 16 -1 (3850 3200)(3400 3200);
WIRE 16 -1 (2950 3125)(2950 3200);
WIRE 16 -1 (3400 3200)(2950 3200);
WIRE 16 -1 (2500 3200)(2500 3125);
WIRE 16 -1 (2950 3200)(2500 3200);
WIRE 16 -1 (2050 3125)(2050 3200);
WIRE 16 -1 (2500 3200)(2050 3200);
WIRE 16 -1 (1600 3125)(1600 3200);
WIRE 16 -1 (2050 3200)(1600 3200);
WIRE 16 -1 (1150 3200)(1150 3125);
WIRE 16 -1 (1600 3200)(1150 3200);
WIRE 16 -1 (1150 3200)(700 3200);
WIRE 16 -1 (700 3125)(700 3200);
WIRE 16 -1 (250 -1550)(250 -1475);
WIRE 16 -1 (-200 -1550)(-200 -1475);
WIRE 16 -1 (250 -1475)(-200 -1475);
WIRE 16 -1 (-650 -1475)(-650 -1550);
WIRE 16 -1 (-200 -1475)(-650 -1475);
WIRE 16 -1 (-1100 -1550)(-1100 -1475);
WIRE 16 -1 (-650 -1475)(-1100 -1475);
WIRE 16 -1 (-1550 -1550)(-1550 -1475);
WIRE 16 -1 (-1100 -1475)(-1550 -1475);
WIRE 16 -1 (-2000 -1475)(-2000 -1550);
WIRE 16 -1 (-1550 -1475)(-2000 -1475);
WIRE 16 -1 (-2450 -1550)(-2450 -1475);
WIRE 16 -1 (-2000 -1475)(-2450 -1475);
WIRE 16 -1 (-2900 -1550)(-2900 -1475);
WIRE 16 -1 (-2450 -1475)(-2900 -1475);
WIRE 16 -1 (-3350 -1475)(-3350 -1550);
WIRE 16 -1 (-2900 -1475)(-3350 -1475);
WIRE 16 -1 (-3350 -1475)(-3800 -1475);
WIRE 16 -1 (-3800 -1550)(-3800 -1475);
WIRE 16 -1 (-200 -1075)(-200 -950);
WIRE 16 -1 (-200 -1075)(-650 -1075);
WIRE 16 -1 (-650 -1075)(-650 -950);
WIRE 16 -1 (-1100 -1075)(-1100 -950);
WIRE 16 -1 (-650 -1075)(-1100 -1075);
WIRE 16 -1 (-1100 -1075)(-1550 -1075);
WIRE 16 -1 (-1550 -1075)(-1550 -950);
WIRE 16 -1 (-1550 -1075)(-2000 -1075);
WIRE 16 -1 (-2000 -1075)(-2000 -950);
WIRE 16 -1 (-225 2350)(-225 2425);
WIRE 16 -1 (-675 2425)(-675 2350);
WIRE 16 -1 (-225 2425)(-675 2425);
WIRE 16 -1 (-1125 2350)(-1125 2425);
WIRE 16 -1 (-675 2425)(-1125 2425);
WIRE 16 -1 (-1575 2350)(-1575 2425);
WIRE 16 -1 (-1125 2425)(-1575 2425);
WIRE 16 -1 (-2025 2425)(-2025 2350);
WIRE 16 -1 (-1575 2425)(-2025 2425);
WIRE 16 -1 (-2475 2350)(-2475 2425);
WIRE 16 -1 (-2025 2425)(-2475 2425);
WIRE 16 -1 (-2925 2350)(-2925 2425);
WIRE 16 -1 (-2475 2425)(-2925 2425);
WIRE 16 -1 (-3375 2425)(-3375 2350);
WIRE 16 -1 (-2925 2425)(-3375 2425);
WIRE 16 -1 (-3375 2425)(-3825 2425);
WIRE 16 -1 (-3825 2350)(-3825 2425);
WIRE 16 -1 (4325 1275)(4325 1400);
WIRE 16 -1 (3875 1275)(3875 1400);
WIRE 16 -1 (4325 1275)(3875 1275);
WIRE 16 -1 (3425 1275)(3425 1400);
WIRE 16 -1 (3875 1275)(3425 1275);
WIRE 16 -1 (275 1275)(275 1400);
WIRE 16 -1 (725 1275)(275 1275);
WIRE 16 -1 (725 1275)(725 1400);
WIRE 16 -1 (2975 1275)(2975 1400);
WIRE 16 -1 (3425 1275)(2975 1275);
WIRE 16 -1 (2525 1275)(2525 1400);
WIRE 16 -1 (2975 1275)(2525 1275);
WIRE 16 -1 (1175 1275)(725 1275);
WIRE 16 -1 (1175 1275)(1175 1400);
WIRE 16 -1 (1625 1275)(1175 1275);
WIRE 16 -1 (1625 1275)(1625 1400);
WIRE 16 -1 (2075 1275)(2075 1400);
WIRE 16 -1 (2525 1275)(2075 1275);
WIRE 16 -1 (2075 1275)(1625 1275);
WIRE 16 -1 (-225 2025)(-225 2150);
WIRE 16 -1 (-225 2025)(-675 2025);
WIRE 16 -1 (-675 2025)(-675 2150);
WIRE 16 -1 (-675 2025)(-1125 2025);
WIRE 16 -1 (-1125 2025)(-1125 2150);
WIRE 16 -1 (-1125 2025)(-1575 2025);
WIRE 16 -1 (-1575 2025)(-1575 2150);
WIRE 16 -1 (-1575 2025)(-2025 2025);
WIRE 16 -1 (-2025 2025)(-2025 2150);
WIRE 16 -1 (-2475 2025)(-2475 2150);
WIRE 16 -1 (-2025 2025)(-2475 2025);
WIRE 16 -1 (-2475 2025)(-2925 2025);
WIRE 16 -1 (-2925 2025)(-2925 2150);
WIRE 16 -1 (-2925 2025)(-3375 2025);
WIRE 16 -1 (-3375 2025)(-3375 2150);
WIRE 16 -1 (-4275 2025)(-4275 2150);
WIRE 16 -1 (-3825 2025)(-4275 2025);
WIRE 16 -1 (-3375 2025)(-3825 2025);
WIRE 16 -1 (-3825 2025)(-3825 2150);
WIRE 16 -1 (-4250 -1075)(-4250 -950);
WIRE 16 -1 (-3800 -1075)(-4250 -1075);
WIRE 16 -1 (-3800 -1075)(-3800 -950);
WIRE 16 -1 (-3350 -1075)(-3800 -1075);
WIRE 16 -1 (-3350 -1075)(-3350 -950);
WIRE 16 -1 (-2900 -1075)(-3350 -1075);
WIRE 16 -1 (-2900 -950)(-2900 -1075);
WIRE 16 -1 (-4250 -1875)(-4250 -1750);
WIRE 16 -1 (-3800 -1875)(-4250 -1875);
WIRE 16 -1 (-3800 -1875)(-3800 -1750);
WIRE 16 -1 (-3350 -1875)(-3800 -1875);
WIRE 16 -1 (-3350 -1875)(-3350 -1750);
WIRE 16 -1 (-2900 -1875)(-3350 -1875);
WIRE 16 -1 (-2900 -1875)(-2900 -1750);
WIRE 16 -1 (-2450 -1875)(-2900 -1875);
WIRE 16 -1 (-2450 -1875)(-2450 -1750);
WIRE 16 -1 (-2000 -1875)(-2450 -1875);
WIRE 16 -1 (-2000 -1875)(-2000 -1750);
WIRE 16 -1 (-1550 -1875)(-2000 -1875);
WIRE 16 -1 (-1550 -1875)(-1550 -1750);
WIRE 16 -1 (-1100 -1875)(-1550 -1875);
WIRE 16 -1 (-1100 -1875)(-1100 -1750);
WIRE 16 -1 (-650 -1875)(-1100 -1875);
WIRE 16 -1 (-650 -1875)(-650 -1750);
WIRE 16 -1 (-200 -1875)(-650 -1875);
WIRE 16 -1 (-200 -1875)(-200 -1750);
WIRE 16 -1 (250 -1875)(-200 -1875);
WIRE 16 -1 (250 -1875)(250 -1750);
DOT 1 (-3350 125);
DOT 1 (3400 3200);
DOT 1 (4300 2025);
DOT 1 (4325 1275);
DOT 1 (3850 2800);
DOT 1 (3850 2425);
DOT 1 (3850 2025);
DOT 1 (3400 2800);
DOT 1 (3400 2425);
DOT 1 (3400 2025);
DOT 1 (3875 1675);
DOT 1 (3875 1275);
DOT 1 (3425 1675);
DOT 1 (3425 1275);
DOT 1 (4325 500);
DOT 1 (3875 900);
DOT 1 (3875 500);
DOT 1 (3425 900);
DOT 1 (3425 500);
DOT 1 (2950 3200);
DOT 1 (2500 3200);
DOT 1 (2050 3200);
DOT 1 (1600 3200);
DOT 1 (1150 3200);
DOT 1 (700 3200);
DOT 1 (250 3200);
DOT 1 (-675 3200);
DOT 1 (2950 2800);
DOT 1 (2950 2425);
DOT 1 (2950 2025);
DOT 1 (2500 2800);
DOT 1 (2050 2800);
DOT 1 (2500 2425);
DOT 1 (2500 2025);
DOT 1 (2050 2425);
DOT 1 (2050 2025);
DOT 1 (2975 1675);
DOT 1 (2525 1675);
DOT 1 (2975 1275);
DOT 1 (2525 1275);
DOT 1 (2075 1675);
DOT 1 (2075 1275);
DOT 1 (1600 2800);
DOT 1 (1600 2425);
DOT 1 (1600 2025);
DOT 1 (1150 2800);
DOT 1 (1150 2425);
DOT 1 (1150 2025);
DOT 1 (1625 1675);
DOT 1 (1625 1275);
DOT 1 (1175 1675);
DOT 1 (1175 1275);
DOT 1 (2975 900);
DOT 1 (2975 500);
DOT 1 (2525 900);
DOT 1 (2525 500);
DOT 1 (2075 900);
DOT 1 (2075 500);
DOT 1 (1625 900);
DOT 1 (1625 500);
DOT 1 (1175 900);
DOT 1 (1175 500);
DOT 1 (1925 -675);
DOT 1 (1475 -675);
DOT 1 (1025 -675);
DOT 1 (700 2800);
DOT 1 (700 2425);
DOT 1 (700 2025);
DOT 1 (250 2425);
DOT 1 (725 1675);
DOT 1 (725 1275);
DOT 1 (275 1675);
DOT 1 (-225 2800);
DOT 1 (-225 2025);
DOT 1 (-675 2800);
DOT 1 (-675 2425);
DOT 1 (-675 2025);
DOT 1 (-200 1275);
DOT 1 (-650 1675);
DOT 1 (-650 1275);
DOT 1 (725 500);
DOT 1 (725 900);
DOT 1 (275 900);
DOT 1 (-200 500);
DOT 1 (-650 900);
DOT 1 (-650 500);
DOT 1 (-650 125);
DOT 1 (-200 -275);
DOT 1 (-650 -275);
DOT 1 (-650 -675);
DOT 1 (2375 -1075);
DOT 1 (1475 -1075);
DOT 1 (1925 -1075);
DOT 1 (250 -1875);
DOT 1 (-200 -1075);
DOT 1 (-200 -1475);
DOT 1 (-200 -1875);
DOT 1 (-650 -1475);
DOT 1 (-650 -1075);
DOT 1 (-650 -1875);
DOT 1 (-1125 3200);
DOT 1 (-1575 3200);
DOT 1 (-2025 3200);
DOT 1 (-2475 3200);
DOT 1 (-2925 3200);
DOT 1 (-3375 3200);
DOT 1 (-3825 3200);
DOT 1 (-4275 3200);
DOT 1 (-1125 2800);
DOT 1 (-1125 2425);
DOT 1 (-1125 2025);
DOT 1 (-1575 2425);
DOT 1 (-1575 2025);
DOT 1 (-1575 2800);
DOT 1 (-2025 2800);
DOT 1 (-2025 2425);
DOT 1 (-2025 2025);
DOT 1 (-1100 1675);
DOT 1 (-1550 1675);
DOT 1 (-1100 1275);
DOT 1 (-1550 1275);
DOT 1 (-2000 1675);
DOT 1 (-2000 1275);
DOT 1 (-2475 2800);
DOT 1 (-2475 2425);
DOT 1 (-2475 2025);
DOT 1 (-2925 2800);
DOT 1 (-2925 2425);
DOT 1 (-2925 2025);
DOT 1 (-2450 1675);
DOT 1 (-2450 1275);
DOT 1 (-2900 1675);
DOT 1 (-2900 1275);
DOT 1 (-1100 900);
DOT 1 (-1100 500);
DOT 1 (-1550 900);
DOT 1 (-1550 500);
DOT 1 (-1100 125);
DOT 1 (-1550 125);
DOT 1 (-2000 900);
DOT 1 (-2000 500);
DOT 1 (-2000 125);
DOT 1 (-1100 -275);
DOT 1 (-1550 -275);
DOT 1 (-1100 -675);
DOT 1 (-1550 -675);
DOT 1 (-2000 -275);
DOT 1 (-2000 -675);
DOT 1 (-2450 900);
DOT 1 (-2450 500);
DOT 1 (-2450 125);
DOT 1 (-2900 900);
DOT 1 (-2900 500);
DOT 1 (-2900 125);
DOT 1 (-2450 -275);
DOT 1 (-2900 -275);
DOT 1 (-3375 2800);
DOT 1 (-3375 2025);
DOT 1 (-3375 2425);
DOT 1 (-3825 2800);
DOT 1 (-3825 2425);
DOT 1 (-3825 2025);
DOT 1 (-3350 1675);
DOT 1 (-3350 1275);
DOT 1 (-3800 1675);
DOT 1 (-3800 1275);
DOT 1 (-4275 2425);
DOT 1 (-4250 1675);
DOT 1 (-3350 900);
DOT 1 (-3350 500);
DOT 1 (-3800 900);
DOT 1 (-3800 500);
DOT 1 (-3800 125);
DOT 1 (-3350 -275);
DOT 1 (-3350 -675);
DOT 1 (-3800 -275);
DOT 1 (-3800 -675);
DOT 1 (-4250 900);
DOT 1 (-4250 125);
DOT 1 (-4250 -675);
DOT 1 (-1100 -1075);
DOT 1 (-1100 -1475);
DOT 1 (-1550 -1475);
DOT 1 (-1550 -1075);
DOT 1 (-1100 -1875);
DOT 1 (-1550 -1875);
DOT 1 (-2000 -1475);
DOT 1 (-2000 -1875);
DOT 1 (-2450 -1475);
DOT 1 (-2450 -1875);
DOT 1 (-2900 -1075);
DOT 1 (-2900 -1475);
DOT 1 (-2900 -1875);
DOT 1 (-3350 -1075);
DOT 1 (-3350 -1475);
DOT 1 (-3350 -1875);
DOT 1 (-3800 -1075);
DOT 1 (-3800 -1475);
DOT 1 (-3800 -1875);
DOT 1 (-4250 -1475);
FORCENOTE
PVCCIN: 79 0402 22UF CAPS ON TOP
(-3375 3250) 0;
DISPLAY LEFT (-3375 3250);
DISPLAY 1.021277 (-3375 3250);
PAINT SKYBLUE (-3375 3250);
FORCENOTE
PVCCIN: 10 0805 100UF MLCC CAPS ON TOP
(-3350 200) 0;
DISPLAY LEFT (-3350 200);
DISPLAY 1.021277 (-3350 200);
PAINT SKYBLUE (-3350 200);
QUIT
